FILE_TYPE = MACRO_DRAWING;
SET COLOR_WIRE YELLOW;
SET COLOR_PROP ORANGE;
SET COLOR_DOT WHITE;
SET COLOR_ARC YELLOW;
SET COLOR_BODY GREEN;
SET COLOR_NOTE PURPLE;
SET PROP_DISPLAY VALUE;
SET PAGE_NUMBER P101;
FORCEADD OFFPAGE..2
R 2
(-5200 700);
FORCEPROP 2 LAST $XR0 101 
J 0
(-5455 700);
DISPLAY 0.638298 (-5455 700);
PAINT MONO (-5455 700);
FORCEPROP 2 LAST CDS_LIB standard
J 0
(-5200 700);
PAINT MONO (-5200 700);
DISPLAY INVISIBLE (-5200 700);
FORCEPROP 1 LAST OFFPAGE TRUE
J 2
(-5525 575);
DISPLAY 0.872340 (-5525 575);
DISPLAY INVISIBLE (-5525 575);
FORCEPROP 1 LAST COMMENT_BODY TRUE
J 2
(-5155 605);
DISPLAY 0.872340 (-5155 605);
PAINT GREEN (-5155 605);
DISPLAY INVISIBLE (-5155 605);
FORCEPROP 2 LAST PATH I1
J 0
(-5150 775);
DISPLAY 1.021277 (-5150 775);
DISPLAY INVISIBLE (-5150 775);
FORCEADD OFFPAGE..3
R 2
(-5200 2825);
FORCEPROP 2 LAST $XR1 100 
J 0
(-5569 2825);
DISPLAY 0.638298 (-5569 2825);
PAINT MONO (-5569 2825);
FORCEPROP 2 LAST $XR0 52 
J 0
(-5449 2825);
DISPLAY 0.638298 (-5449 2825);
PAINT MONO (-5449 2825);
FORCEPROP 2 LAST CDS_LIB standard
J 0
(-5200 2825);
PAINT MONO (-5200 2825);
DISPLAY INVISIBLE (-5200 2825);
FORCEPROP 1 LAST OFFPAGE TRUE
J 2
(-5525 2700);
DISPLAY 0.872340 (-5525 2700);
DISPLAY INVISIBLE (-5525 2700);
FORCEPROP 1 LAST COMMENT_BODY TRUE
J 2
(-5150 2725);
DISPLAY 0.872340 (-5150 2725);
PAINT GREEN (-5150 2725);
DISPLAY INVISIBLE (-5150 2725);
FORCEPROP 2 LAST PATH I10
J 0
(-5150 2900);
DISPLAY 1.021277 (-5150 2900);
DISPLAY INVISIBLE (-5150 2900);
FORCEADD TAP..1
(-2625 4100);
FORCEPROP 3 LASTPIN (-2675 4100) SIG_NAME M_B_CPU1_SA_DQ<20>
J 0
(-2665 4110);
DISPLAY 0.659574 (-2665 4110);
PAINT MONO (-2665 4110);
DISPLAY INVISIBLE (-2665 4110);
FORCEPROP 1 LASTPIN (-2675 4100) BN 20
J 0
(-2687 4108);
DISPLAY 0.680851 (-2687 4108);
PAINT GREEN (-2687 4108);
FORCEPROP 2 LAST CDS_LIB standard
J 0
(-2625 4100);
PAINT MONO (-2625 4100);
DISPLAY INVISIBLE (-2625 4100);
FORCEPROP 1 LAST BODY_TYPE PLUMBING
J 0
(-2625 4150);
DISPLAY 0.872340 (-2625 4150);
PAINT GREEN (-2625 4150);
DISPLAY INVISIBLE (-2625 4150);
FORCEPROP 1 LAST HDL_TAP TRUE
J 0
(-2300 3975);
DISPLAY 0.872340 (-2300 3975);
DISPLAY INVISIBLE (-2300 3975);
FORCEPROP 1 LAST PATH I100
J 0
(-2627 4100);
DISPLAY 0.872340 (-2627 4100);
PAINT GREEN (-2627 4100);
DISPLAY INVISIBLE (-2627 4100);
FORCEADD TAP..1
(-2625 4150);
FORCEPROP 3 LASTPIN (-2675 4150) SIG_NAME M_B_CPU1_SA_DQ<21>
J 0
(-2665 4160);
DISPLAY 0.659574 (-2665 4160);
PAINT MONO (-2665 4160);
DISPLAY INVISIBLE (-2665 4160);
FORCEPROP 1 LASTPIN (-2675 4150) BN 21
J 0
(-2687 4158);
DISPLAY 0.680851 (-2687 4158);
PAINT GREEN (-2687 4158);
FORCEPROP 2 LAST CDS_LIB standard
J 0
(-2625 4150);
PAINT MONO (-2625 4150);
DISPLAY INVISIBLE (-2625 4150);
FORCEPROP 1 LAST BODY_TYPE PLUMBING
J 0
(-2625 4200);
DISPLAY 0.872340 (-2625 4200);
PAINT GREEN (-2625 4200);
DISPLAY INVISIBLE (-2625 4200);
FORCEPROP 1 LAST HDL_TAP TRUE
J 0
(-2300 4025);
DISPLAY 0.872340 (-2300 4025);
DISPLAY INVISIBLE (-2300 4025);
FORCEPROP 1 LAST PATH I101
J 0
(-2627 4150);
DISPLAY 0.872340 (-2627 4150);
PAINT GREEN (-2627 4150);
DISPLAY INVISIBLE (-2627 4150);
FORCEADD TAP..1
(-2625 4200);
FORCEPROP 3 LASTPIN (-2675 4200) SIG_NAME M_B_CPU1_SA_DQ<22>
J 0
(-2665 4210);
DISPLAY 0.659574 (-2665 4210);
PAINT MONO (-2665 4210);
DISPLAY INVISIBLE (-2665 4210);
FORCEPROP 1 LASTPIN (-2675 4200) BN 22
J 0
(-2687 4208);
DISPLAY 0.680851 (-2687 4208);
PAINT GREEN (-2687 4208);
FORCEPROP 2 LAST CDS_LIB standard
J 0
(-2625 4200);
DISPLAY INVISIBLE (-2625 4200);
FORCEPROP 1 LAST BODY_TYPE PLUMBING
J 0
(-2625 4250);
DISPLAY 0.872340 (-2625 4250);
PAINT GREEN (-2625 4250);
DISPLAY INVISIBLE (-2625 4250);
FORCEPROP 1 LAST HDL_TAP TRUE
J 0
(-2300 4075);
DISPLAY 0.872340 (-2300 4075);
DISPLAY INVISIBLE (-2300 4075);
FORCEPROP 1 LAST PATH I102
J 0
(-2627 4200);
DISPLAY 0.872340 (-2627 4200);
PAINT GREEN (-2627 4200);
DISPLAY INVISIBLE (-2627 4200);
FORCEADD TAP..1
(-2625 4250);
FORCEPROP 3 LASTPIN (-2675 4250) SIG_NAME M_B_CPU1_SA_DQ<23>
J 0
(-2665 4260);
DISPLAY 0.659574 (-2665 4260);
PAINT MONO (-2665 4260);
DISPLAY INVISIBLE (-2665 4260);
FORCEPROP 1 LASTPIN (-2675 4250) BN 23
J 0
(-2687 4258);
DISPLAY 0.680851 (-2687 4258);
PAINT GREEN (-2687 4258);
FORCEPROP 2 LAST CDS_LIB standard
J 0
(-2625 4250);
DISPLAY INVISIBLE (-2625 4250);
FORCEPROP 1 LAST BODY_TYPE PLUMBING
J 0
(-2625 4300);
DISPLAY 0.872340 (-2625 4300);
PAINT GREEN (-2625 4300);
DISPLAY INVISIBLE (-2625 4300);
FORCEPROP 1 LAST HDL_TAP TRUE
J 0
(-2300 4125);
DISPLAY 0.872340 (-2300 4125);
DISPLAY INVISIBLE (-2300 4125);
FORCEPROP 1 LAST PATH I103
J 0
(-2627 4250);
DISPLAY 0.872340 (-2627 4250);
PAINT GREEN (-2627 4250);
DISPLAY INVISIBLE (-2627 4250);
FORCEADD TAP..1
(-2625 4300);
FORCEPROP 3 LASTPIN (-2675 4300) SIG_NAME M_B_CPU1_SA_DQ<24>
J 0
(-2665 4310);
DISPLAY 0.659574 (-2665 4310);
PAINT MONO (-2665 4310);
DISPLAY INVISIBLE (-2665 4310);
FORCEPROP 1 LASTPIN (-2675 4300) BN 24
J 0
(-2687 4308);
DISPLAY 0.680851 (-2687 4308);
PAINT GREEN (-2687 4308);
FORCEPROP 2 LAST CDS_LIB standard
J 0
(-2625 4300);
DISPLAY INVISIBLE (-2625 4300);
FORCEPROP 1 LAST BODY_TYPE PLUMBING
J 0
(-2625 4350);
DISPLAY 0.872340 (-2625 4350);
PAINT GREEN (-2625 4350);
DISPLAY INVISIBLE (-2625 4350);
FORCEPROP 1 LAST HDL_TAP TRUE
J 0
(-2300 4175);
DISPLAY 0.872340 (-2300 4175);
DISPLAY INVISIBLE (-2300 4175);
FORCEPROP 1 LAST PATH I104
J 0
(-2627 4300);
DISPLAY 0.872340 (-2627 4300);
PAINT GREEN (-2627 4300);
DISPLAY INVISIBLE (-2627 4300);
FORCEADD OFFPAGE..1
(-5200 4675);
FORCEPROP 2 LAST $XR1 100 
J 0
(-5541 4675);
DISPLAY 0.638298 (-5541 4675);
PAINT MONO (-5541 4675);
FORCEPROP 2 LAST $XR0 52 
J 0
(-5421 4675);
DISPLAY 0.638298 (-5421 4675);
PAINT MONO (-5421 4675);
FORCEPROP 2 LAST CDS_LIB standard
J 0
(-5200 4675);
PAINT MONO (-5200 4675);
DISPLAY INVISIBLE (-5200 4675);
FORCEPROP 1 LAST OFFPAGE TRUE
J 0
(-4875 4550);
DISPLAY 0.872340 (-4875 4550);
DISPLAY INVISIBLE (-4875 4550);
FORCEPROP 1 LAST COMMENT_BODY TRUE
J 0
(-5075 4575);
DISPLAY 0.872340 (-5075 4575);
PAINT GREEN (-5075 4575);
DISPLAY INVISIBLE (-5075 4575);
FORCEPROP 2 LAST PATH I105
J 0
(-5150 4750);
DISPLAY 1.021277 (-5150 4750);
DISPLAY INVISIBLE (-5150 4750);
FORCEADD TAP..1
R 2
(-4275 4350);
FORCEPROP 3 LASTPIN (-4225 4350) SIG_NAME M_B_CPU1_SA_CA<0>
J 0
(-4215 4360);
DISPLAY 0.659574 (-4215 4360);
PAINT MONO (-4215 4360);
DISPLAY INVISIBLE (-4215 4360);
FORCEPROP 1 LASTPIN (-4225 4350) BN 0
J 2
(-4213 4358);
DISPLAY 0.680851 (-4213 4358);
PAINT GREEN (-4213 4358);
FORCEPROP 2 LAST CDS_LIB standard
J 0
(-4275 4350);
DISPLAY INVISIBLE (-4275 4350);
FORCEPROP 1 LAST BODY_TYPE PLUMBING
J 2
(-4275 4400);
DISPLAY 0.872340 (-4275 4400);
PAINT GREEN (-4275 4400);
DISPLAY INVISIBLE (-4275 4400);
FORCEPROP 1 LAST HDL_TAP TRUE
J 2
(-4600 4225);
DISPLAY 0.872340 (-4600 4225);
DISPLAY INVISIBLE (-4600 4225);
FORCEPROP 1 LAST PATH I106
J 2
(-4273 4350);
DISPLAY 0.872340 (-4273 4350);
PAINT GREEN (-4273 4350);
DISPLAY INVISIBLE (-4273 4350);
FORCEADD TAP..1
R 2
(-4275 4400);
FORCEPROP 3 LASTPIN (-4225 4400) SIG_NAME M_B_CPU1_SA_CA<1>
J 0
(-4215 4410);
DISPLAY 0.659574 (-4215 4410);
PAINT MONO (-4215 4410);
DISPLAY INVISIBLE (-4215 4410);
FORCEPROP 1 LASTPIN (-4225 4400) BN 1
J 2
(-4213 4408);
DISPLAY 0.680851 (-4213 4408);
PAINT GREEN (-4213 4408);
FORCEPROP 2 LAST CDS_LIB standard
J 0
(-4275 4400);
DISPLAY INVISIBLE (-4275 4400);
FORCEPROP 1 LAST BODY_TYPE PLUMBING
J 2
(-4275 4450);
DISPLAY 0.872340 (-4275 4450);
PAINT GREEN (-4275 4450);
DISPLAY INVISIBLE (-4275 4450);
FORCEPROP 1 LAST HDL_TAP TRUE
J 2
(-4600 4275);
DISPLAY 0.872340 (-4600 4275);
DISPLAY INVISIBLE (-4600 4275);
FORCEPROP 1 LAST PATH I107
J 2
(-4273 4400);
DISPLAY 0.872340 (-4273 4400);
PAINT GREEN (-4273 4400);
DISPLAY INVISIBLE (-4273 4400);
FORCEADD TAP..1
R 2
(-4275 4550);
FORCEPROP 3 LASTPIN (-4225 4550) SIG_NAME M_B_CPU1_SA_CA<4>
J 0
(-4215 4560);
DISPLAY 0.659574 (-4215 4560);
PAINT MONO (-4215 4560);
DISPLAY INVISIBLE (-4215 4560);
FORCEPROP 1 LASTPIN (-4225 4550) BN 4
J 2
(-4213 4558);
DISPLAY 0.680851 (-4213 4558);
PAINT GREEN (-4213 4558);
FORCEPROP 2 LAST CDS_LIB standard
J 0
(-4275 4550);
DISPLAY INVISIBLE (-4275 4550);
FORCEPROP 1 LAST BODY_TYPE PLUMBING
J 2
(-4275 4600);
DISPLAY 0.872340 (-4275 4600);
PAINT GREEN (-4275 4600);
DISPLAY INVISIBLE (-4275 4600);
FORCEPROP 1 LAST HDL_TAP TRUE
J 2
(-4600 4425);
DISPLAY 0.872340 (-4600 4425);
DISPLAY INVISIBLE (-4600 4425);
FORCEPROP 1 LAST PATH I108
J 2
(-4273 4550);
DISPLAY 0.872340 (-4273 4550);
PAINT GREEN (-4273 4550);
DISPLAY INVISIBLE (-4273 4550);
FORCEADD TAP..1
R 2
(-4275 4500);
FORCEPROP 3 LASTPIN (-4225 4500) SIG_NAME M_B_CPU1_SA_CA<3>
J 0
(-4215 4510);
DISPLAY 0.659574 (-4215 4510);
PAINT MONO (-4215 4510);
DISPLAY INVISIBLE (-4215 4510);
FORCEPROP 1 LASTPIN (-4225 4500) BN 3
J 2
(-4213 4508);
DISPLAY 0.680851 (-4213 4508);
PAINT GREEN (-4213 4508);
FORCEPROP 2 LAST CDS_LIB standard
J 0
(-4275 4500);
DISPLAY INVISIBLE (-4275 4500);
FORCEPROP 1 LAST BODY_TYPE PLUMBING
J 2
(-4275 4550);
DISPLAY 0.872340 (-4275 4550);
PAINT GREEN (-4275 4550);
DISPLAY INVISIBLE (-4275 4550);
FORCEPROP 1 LAST HDL_TAP TRUE
J 2
(-4600 4375);
DISPLAY 0.872340 (-4600 4375);
DISPLAY INVISIBLE (-4600 4375);
FORCEPROP 1 LAST PATH I109
J 2
(-4273 4500);
DISPLAY 0.872340 (-4273 4500);
PAINT GREEN (-4273 4500);
DISPLAY INVISIBLE (-4273 4500);
FORCEADD OFFPAGE..3
R 2
(-5200 3275);
FORCEPROP 2 LAST $XR1 100 
J 0
(-5569 3275);
DISPLAY 0.638298 (-5569 3275);
PAINT MONO (-5569 3275);
FORCEPROP 2 LAST $XR0 52 
J 0
(-5449 3275);
DISPLAY 0.638298 (-5449 3275);
PAINT MONO (-5449 3275);
FORCEPROP 2 LAST CDS_LIB standard
J 0
(-5200 3275);
PAINT MONO (-5200 3275);
DISPLAY INVISIBLE (-5200 3275);
FORCEPROP 1 LAST OFFPAGE TRUE
J 2
(-5525 3150);
DISPLAY 0.872340 (-5525 3150);
DISPLAY INVISIBLE (-5525 3150);
FORCEPROP 1 LAST COMMENT_BODY TRUE
J 2
(-5150 3175);
DISPLAY 0.872340 (-5150 3175);
PAINT GREEN (-5150 3175);
DISPLAY INVISIBLE (-5150 3175);
FORCEPROP 2 LAST PATH I11
J 0
(-5150 3350);
DISPLAY 1.021277 (-5150 3350);
DISPLAY INVISIBLE (-5150 3350);
FORCEADD TAP..1
R 2
(-4275 4450);
FORCEPROP 3 LASTPIN (-4225 4450) SIG_NAME M_B_CPU1_SA_CA<2>
J 0
(-4215 4460);
DISPLAY 0.659574 (-4215 4460);
PAINT MONO (-4215 4460);
DISPLAY INVISIBLE (-4215 4460);
FORCEPROP 1 LASTPIN (-4225 4450) BN 2
J 2
(-4213 4458);
DISPLAY 0.680851 (-4213 4458);
PAINT GREEN (-4213 4458);
FORCEPROP 2 LAST CDS_LIB standard
J 0
(-4275 4450);
DISPLAY INVISIBLE (-4275 4450);
FORCEPROP 1 LAST BODY_TYPE PLUMBING
J 2
(-4275 4500);
DISPLAY 0.872340 (-4275 4500);
PAINT GREEN (-4275 4500);
DISPLAY INVISIBLE (-4275 4500);
FORCEPROP 1 LAST HDL_TAP TRUE
J 2
(-4600 4325);
DISPLAY 0.872340 (-4600 4325);
DISPLAY INVISIBLE (-4600 4325);
FORCEPROP 1 LAST PATH I110
J 2
(-4273 4450);
DISPLAY 0.872340 (-4273 4450);
PAINT GREEN (-4273 4450);
DISPLAY INVISIBLE (-4273 4450);
FORCEADD TAP..1
R 2
(-4275 4600);
FORCEPROP 3 LASTPIN (-4225 4600) SIG_NAME M_B_CPU1_SA_CA<5>
J 0
(-4215 4610);
DISPLAY 0.659574 (-4215 4610);
PAINT MONO (-4215 4610);
DISPLAY INVISIBLE (-4215 4610);
FORCEPROP 1 LASTPIN (-4225 4600) BN 5
J 2
(-4213 4608);
DISPLAY 0.680851 (-4213 4608);
PAINT GREEN (-4213 4608);
FORCEPROP 2 LAST CDS_LIB standard
J 0
(-4275 4600);
DISPLAY INVISIBLE (-4275 4600);
FORCEPROP 1 LAST BODY_TYPE PLUMBING
J 2
(-4275 4650);
DISPLAY 0.872340 (-4275 4650);
PAINT GREEN (-4275 4650);
DISPLAY INVISIBLE (-4275 4650);
FORCEPROP 1 LAST HDL_TAP TRUE
J 2
(-4600 4475);
DISPLAY 0.872340 (-4600 4475);
DISPLAY INVISIBLE (-4600 4475);
FORCEPROP 1 LAST PATH I111
J 2
(-4273 4600);
DISPLAY 0.872340 (-4273 4600);
PAINT GREEN (-4273 4600);
DISPLAY INVISIBLE (-4273 4600);
FORCEADD TAP..1
R 2
(-4275 4650);
FORCEPROP 3 LASTPIN (-4225 4650) SIG_NAME M_B_CPU1_SA_CA<6>
J 0
(-4215 4660);
DISPLAY 0.659574 (-4215 4660);
PAINT MONO (-4215 4660);
DISPLAY INVISIBLE (-4215 4660);
FORCEPROP 1 LASTPIN (-4225 4650) BN 6
J 2
(-4213 4658);
DISPLAY 0.680851 (-4213 4658);
PAINT GREEN (-4213 4658);
FORCEPROP 2 LAST CDS_LIB standard
J 0
(-4275 4650);
DISPLAY INVISIBLE (-4275 4650);
FORCEPROP 1 LAST BODY_TYPE PLUMBING
J 2
(-4275 4700);
DISPLAY 0.872340 (-4275 4700);
PAINT GREEN (-4275 4700);
DISPLAY INVISIBLE (-4275 4700);
FORCEPROP 1 LAST HDL_TAP TRUE
J 2
(-4600 4525);
DISPLAY 0.872340 (-4600 4525);
DISPLAY INVISIBLE (-4600 4525);
FORCEPROP 1 LAST PATH I112
J 2
(-4273 4650);
DISPLAY 0.872340 (-4273 4650);
PAINT GREEN (-4273 4650);
DISPLAY INVISIBLE (-4273 4650);
FORCEADD TAP..1
(-2625 4350);
FORCEPROP 3 LASTPIN (-2675 4350) SIG_NAME M_B_CPU1_SA_DQ<25>
J 0
(-2665 4360);
DISPLAY 0.659574 (-2665 4360);
PAINT MONO (-2665 4360);
DISPLAY INVISIBLE (-2665 4360);
FORCEPROP 1 LASTPIN (-2675 4350) BN 25
J 0
(-2687 4358);
DISPLAY 0.680851 (-2687 4358);
PAINT GREEN (-2687 4358);
FORCEPROP 2 LAST CDS_LIB standard
J 0
(-2625 4350);
DISPLAY INVISIBLE (-2625 4350);
FORCEPROP 1 LAST BODY_TYPE PLUMBING
J 0
(-2625 4400);
DISPLAY 0.872340 (-2625 4400);
PAINT GREEN (-2625 4400);
DISPLAY INVISIBLE (-2625 4400);
FORCEPROP 1 LAST HDL_TAP TRUE
J 0
(-2300 4225);
DISPLAY 0.872340 (-2300 4225);
DISPLAY INVISIBLE (-2300 4225);
FORCEPROP 1 LAST PATH I113
J 0
(-2627 4350);
DISPLAY 0.872340 (-2627 4350);
PAINT GREEN (-2627 4350);
DISPLAY INVISIBLE (-2627 4350);
FORCEADD TAP..1
(-2625 4400);
FORCEPROP 3 LASTPIN (-2675 4400) SIG_NAME M_B_CPU1_SA_DQ<26>
J 0
(-2665 4410);
DISPLAY 0.659574 (-2665 4410);
PAINT MONO (-2665 4410);
DISPLAY INVISIBLE (-2665 4410);
FORCEPROP 1 LASTPIN (-2675 4400) BN 26
J 0
(-2687 4408);
DISPLAY 0.680851 (-2687 4408);
PAINT GREEN (-2687 4408);
FORCEPROP 2 LAST CDS_LIB standard
J 0
(-2625 4400);
DISPLAY INVISIBLE (-2625 4400);
FORCEPROP 1 LAST BODY_TYPE PLUMBING
J 0
(-2625 4450);
DISPLAY 0.872340 (-2625 4450);
PAINT GREEN (-2625 4450);
DISPLAY INVISIBLE (-2625 4450);
FORCEPROP 1 LAST HDL_TAP TRUE
J 0
(-2300 4275);
DISPLAY 0.872340 (-2300 4275);
DISPLAY INVISIBLE (-2300 4275);
FORCEPROP 1 LAST PATH I114
J 0
(-2627 4400);
DISPLAY 0.872340 (-2627 4400);
PAINT GREEN (-2627 4400);
DISPLAY INVISIBLE (-2627 4400);
FORCEADD TAP..1
(-2625 4450);
FORCEPROP 3 LASTPIN (-2675 4450) SIG_NAME M_B_CPU1_SA_DQ<27>
J 0
(-2665 4460);
DISPLAY 0.659574 (-2665 4460);
PAINT MONO (-2665 4460);
DISPLAY INVISIBLE (-2665 4460);
FORCEPROP 1 LASTPIN (-2675 4450) BN 27
J 0
(-2687 4458);
DISPLAY 0.680851 (-2687 4458);
PAINT GREEN (-2687 4458);
FORCEPROP 2 LAST CDS_LIB standard
J 0
(-2625 4450);
DISPLAY INVISIBLE (-2625 4450);
FORCEPROP 1 LAST BODY_TYPE PLUMBING
J 0
(-2625 4500);
DISPLAY 0.872340 (-2625 4500);
PAINT GREEN (-2625 4500);
DISPLAY INVISIBLE (-2625 4500);
FORCEPROP 1 LAST HDL_TAP TRUE
J 0
(-2300 4325);
DISPLAY 0.872340 (-2300 4325);
DISPLAY INVISIBLE (-2300 4325);
FORCEPROP 1 LAST PATH I115
J 0
(-2627 4450);
DISPLAY 0.872340 (-2627 4450);
PAINT GREEN (-2627 4450);
DISPLAY INVISIBLE (-2627 4450);
FORCEADD TAP..1
(-2625 4500);
FORCEPROP 3 LASTPIN (-2675 4500) SIG_NAME M_B_CPU1_SA_DQ<28>
J 0
(-2665 4510);
DISPLAY 0.659574 (-2665 4510);
PAINT MONO (-2665 4510);
DISPLAY INVISIBLE (-2665 4510);
FORCEPROP 1 LASTPIN (-2675 4500) BN 28
J 0
(-2687 4508);
DISPLAY 0.680851 (-2687 4508);
PAINT GREEN (-2687 4508);
FORCEPROP 2 LAST CDS_LIB standard
J 0
(-2625 4500);
DISPLAY INVISIBLE (-2625 4500);
FORCEPROP 1 LAST BODY_TYPE PLUMBING
J 0
(-2625 4550);
DISPLAY 0.872340 (-2625 4550);
PAINT GREEN (-2625 4550);
DISPLAY INVISIBLE (-2625 4550);
FORCEPROP 1 LAST HDL_TAP TRUE
J 0
(-2300 4375);
DISPLAY 0.872340 (-2300 4375);
DISPLAY INVISIBLE (-2300 4375);
FORCEPROP 1 LAST PATH I116
J 0
(-2627 4500);
DISPLAY 0.872340 (-2627 4500);
PAINT GREEN (-2627 4500);
DISPLAY INVISIBLE (-2627 4500);
FORCEADD TAP..1
(-2625 4600);
FORCEPROP 3 LASTPIN (-2675 4600) SIG_NAME M_B_CPU1_SA_DQ<30>
J 0
(-2665 4610);
DISPLAY 0.659574 (-2665 4610);
PAINT MONO (-2665 4610);
DISPLAY INVISIBLE (-2665 4610);
FORCEPROP 1 LASTPIN (-2675 4600) BN 30
J 0
(-2687 4608);
DISPLAY 0.680851 (-2687 4608);
PAINT GREEN (-2687 4608);
FORCEPROP 2 LAST CDS_LIB standard
J 0
(-2625 4600);
DISPLAY INVISIBLE (-2625 4600);
FORCEPROP 1 LAST BODY_TYPE PLUMBING
J 0
(-2625 4650);
DISPLAY 0.872340 (-2625 4650);
PAINT GREEN (-2625 4650);
DISPLAY INVISIBLE (-2625 4650);
FORCEPROP 1 LAST HDL_TAP TRUE
J 0
(-2300 4475);
DISPLAY 0.872340 (-2300 4475);
DISPLAY INVISIBLE (-2300 4475);
FORCEPROP 1 LAST PATH I117
J 0
(-2627 4600);
DISPLAY 0.872340 (-2627 4600);
PAINT GREEN (-2627 4600);
DISPLAY INVISIBLE (-2627 4600);
FORCEADD TAP..1
(-2625 4550);
FORCEPROP 3 LASTPIN (-2675 4550) SIG_NAME M_B_CPU1_SA_DQ<29>
J 0
(-2665 4560);
DISPLAY 0.659574 (-2665 4560);
PAINT MONO (-2665 4560);
DISPLAY INVISIBLE (-2665 4560);
FORCEPROP 1 LASTPIN (-2675 4550) BN 29
J 0
(-2687 4558);
DISPLAY 0.680851 (-2687 4558);
PAINT GREEN (-2687 4558);
FORCEPROP 2 LAST CDS_LIB standard
J 0
(-2625 4550);
DISPLAY INVISIBLE (-2625 4550);
FORCEPROP 1 LAST BODY_TYPE PLUMBING
J 0
(-2625 4600);
DISPLAY 0.872340 (-2625 4600);
PAINT GREEN (-2625 4600);
DISPLAY INVISIBLE (-2625 4600);
FORCEPROP 1 LAST HDL_TAP TRUE
J 0
(-2300 4425);
DISPLAY 0.872340 (-2300 4425);
DISPLAY INVISIBLE (-2300 4425);
FORCEPROP 1 LAST PATH I118
J 0
(-2627 4550);
DISPLAY 0.872340 (-2627 4550);
PAINT GREEN (-2627 4550);
DISPLAY INVISIBLE (-2627 4550);
FORCEADD TAP..1
(-2625 4650);
FORCEPROP 3 LASTPIN (-2675 4650) SIG_NAME M_B_CPU1_SA_DQ<31>
J 0
(-2665 4660);
DISPLAY 0.659574 (-2665 4660);
PAINT MONO (-2665 4660);
DISPLAY INVISIBLE (-2665 4660);
FORCEPROP 1 LASTPIN (-2675 4650) BN 31
J 0
(-2687 4658);
DISPLAY 0.680851 (-2687 4658);
PAINT GREEN (-2687 4658);
FORCEPROP 2 LAST CDS_LIB standard
J 0
(-2625 4650);
DISPLAY INVISIBLE (-2625 4650);
FORCEPROP 1 LAST BODY_TYPE PLUMBING
J 0
(-2625 4700);
DISPLAY 0.872340 (-2625 4700);
PAINT GREEN (-2625 4700);
DISPLAY INVISIBLE (-2625 4700);
FORCEPROP 1 LAST HDL_TAP TRUE
J 0
(-2300 4525);
DISPLAY 0.872340 (-2300 4525);
DISPLAY INVISIBLE (-2300 4525);
FORCEPROP 1 LAST PATH I119
J 0
(-2627 4650);
DISPLAY 0.872340 (-2627 4650);
PAINT GREEN (-2627 4650);
DISPLAY INVISIBLE (-2627 4650);
FORCEADD OFFPAGE..1
(-5200 3350);
FORCEPROP 2 LAST $XR0 52 
J 0
(-5421 3350);
DISPLAY 0.638298 (-5421 3350);
PAINT MONO (-5421 3350);
FORCEPROP 2 LAST CDS_LIB standard
J 0
(-5200 3350);
PAINT MONO (-5200 3350);
DISPLAY INVISIBLE (-5200 3350);
FORCEPROP 1 LAST OFFPAGE TRUE
J 0
(-4875 3225);
DISPLAY 0.872340 (-4875 3225);
DISPLAY INVISIBLE (-4875 3225);
FORCEPROP 1 LAST COMMENT_BODY TRUE
J 0
(-5075 3250);
DISPLAY 0.872340 (-5075 3250);
PAINT GREEN (-5075 3250);
DISPLAY INVISIBLE (-5075 3250);
FORCEPROP 2 LAST PATH I12
J 0
(-5150 3425);
DISPLAY 1.021277 (-5150 3425);
DISPLAY INVISIBLE (-5150 3425);
FORCEADD UNIVERSAL_GND..1
(-900 400);
FORCEPROP 3 LASTPIN (-900 450) SIG_NAME GND\g
J 0
(-890 460);
DISPLAY 0.659574 (-890 460);
PAINT MONO (-890 460);
DISPLAY INVISIBLE (-890 460);
FORCEPROP 1 LAST PATH I120
J 0
(-825 400);
DISPLAY 0.872340 (-825 400);
PAINT AQUA (-825 400);
DISPLAY INVISIBLE (-825 400);
FORCEPROP 1 LAST HDL_POWER GND
J 1
(-875 325);
DISPLAY 0.872340 (-875 325);
PAINT GREEN (-875 325);
DISPLAY INVISIBLE (-875 325);
FORCEPROP 2 LAST CDS_LIB logical_power
J 0
(-900 400);
PAINT MONO (-900 400);
DISPLAY INVISIBLE (-900 400);
FORCEADD Q_CAP..1
(-900 775);
FORCEPROP 1 LAST PART_NUMBER CH5221MEB00
J 0
(-850 625);
DISPLAY 0.978723 (-850 625);
DISPLAY INVISIBLE (-850 625);
FORCEPROP 1 LAST TOLERANCE 20%
J 0
(-850 725);
DISPLAY 0.978723 (-850 725);
FORCEPROP 1 LAST PACK_TYPE C0402
J 0
(-850 575);
DISPLAY 0.978723 (-850 575);
FORCEPROP 1 LAST MATERIAL X6S
J 0
(-850 675);
DISPLAY 0.978723 (-850 675);
FORCEPROP 1 LAST VOLTAGE 6.3V
J 0
(-850 775);
DISPLAY 0.978723 (-850 775);
FORCEPROP 1 LAST VALUE 2.2UF
J 0
(-850 825);
DISPLAY 0.978723 (-850 825);
FORCEPROP 1 LAST $LOCATION C59
J 0
(-850 875);
DISPLAY 0.978723 (-850 875);
FORCEPROP 1 LASTPIN (-900 875) $PN 1
J 0
(-890 855);
DISPLAY 0.787234 (-890 855);
FORCEPROP 1 LASTPIN (-900 675) $PN 2
J 0
(-890 655);
DISPLAY 0.787234 (-890 655);
FORCEPROP 2 LAST CDS_LIB pure_quanta
J 0
(-900 775);
PAINT MONO (-900 775);
DISPLAY INVISIBLE (-900 775);
FORCEPROP 1 LAST PATH I121
J 0
(-850 925);
DISPLAY 0.978723 (-850 925);
PAINT WHITE (-850 925);
DISPLAY INVISIBLE (-850 925);
FORCEPROP 2 LAST CDS_LOCATION C59
J 0
(-850 975);
DISPLAY 1.021277 (-850 975);
DISPLAY INVISIBLE (-850 975);
FORCEPROP 2 LAST $SEC 1
J 0
(-850 975);
DISPLAY 0.680851 (-850 975);
PAINT MONO (-850 975);
DISPLAY INVISIBLE (-850 975);
FORCEPROP 2 LAST CDS_SEC 1
J 0
(-850 975);
DISPLAY 1.021277 (-850 975);
DISPLAY INVISIBLE (-850 975);
FORCEADD VCC_CORE..1
(-900 1100);
FORCEPROP 3 LASTPIN (-900 1050) SIG_NAME P3V3_AUX\g
J 0
(-890 1060);
DISPLAY 0.659574 (-890 1060);
PAINT MONO (-890 1060);
DISPLAY INVISIBLE (-890 1060);
FORCEPROP 1 LAST HDL_POWER P3V3_AUX
J 1
(-900 1150);
DISPLAY 1.148936 (-900 1150);
PAINT GREEN (-900 1150);
FORCEPROP 2 LAST CDS_LIB logical_power
J 0
(-900 1100);
PAINT MONO (-900 1100);
DISPLAY INVISIBLE (-900 1100);
FORCEPROP 1 LAST PATH I122
J 0
(-850 1125);
DISPLAY 0.872340 (-850 1125);
PAINT AQUA (-850 1125);
DISPLAY INVISIBLE (-850 1125);
FORCEADD OFFPAGE..3
(-1800 3025);
FORCEPROP 2 LAST $XR1 100 
J 0
(-1496 3025);
DISPLAY 0.638298 (-1496 3025);
PAINT MONO (-1496 3025);
FORCEPROP 2 LAST $XR0 52 
J 0
(-1586 3025);
DISPLAY 0.638298 (-1586 3025);
PAINT MONO (-1586 3025);
FORCEPROP 2 LAST CDS_LIB standard
J 2
(-1800 3025);
DISPLAY INVISIBLE (-1800 3025);
FORCEPROP 1 LAST OFFPAGE TRUE
J 0
(-1475 2900);
DISPLAY 0.872340 (-1475 2900);
DISPLAY INVISIBLE (-1475 2900);
FORCEPROP 1 LAST COMMENT_BODY TRUE
J 0
(-1850 2925);
DISPLAY 0.872340 (-1850 2925);
PAINT GREEN (-1850 2925);
DISPLAY INVISIBLE (-1850 2925);
FORCEPROP 2 LAST PATH I123
J 0
(-1600 3100);
DISPLAY 1.021277 (-1600 3100);
DISPLAY INVISIBLE (-1600 3100);
FORCEADD Q_CAP..1
(100 775);
FORCEPROP 1 LAST PART_NUMBER CH6103KEA00
J 0
(150 625);
DISPLAY 0.978723 (150 625);
DISPLAY INVISIBLE (150 625);
FORCEPROP 1 LAST TOLERANCE 10%
J 0
(150 725);
DISPLAY 0.978723 (150 725);
FORCEPROP 1 LAST VALUE 10UF
J 0
(150 825);
DISPLAY 0.978723 (150 825);
FORCEPROP 1 LAST PACK_TYPE C0805
J 0
(150 575);
DISPLAY 0.978723 (150 575);
FORCEPROP 1 LAST VOLTAGE 16V
J 0
(150 775);
DISPLAY 0.978723 (150 775);
FORCEPROP 1 LAST MATERIAL X6S
J 0
(150 675);
DISPLAY 0.978723 (150 675);
FORCEPROP 1 LAST $LOCATION C60
J 0
(150 875);
DISPLAY 0.978723 (150 875);
FORCEPROP 1 LASTPIN (100 875) $PN 1
J 0
(110 855);
DISPLAY 0.787234 (110 855);
FORCEPROP 1 LASTPIN (100 675) $PN 2
J 0
(110 655);
DISPLAY 0.787234 (110 655);
FORCEPROP 2 LAST CDS_LIB pure_quanta
J 0
(100 775);
PAINT MONO (100 775);
DISPLAY INVISIBLE (100 775);
FORCEPROP 1 LAST PATH I125
J 0
(150 925);
DISPLAY 0.978723 (150 925);
PAINT WHITE (150 925);
DISPLAY INVISIBLE (150 925);
FORCEPROP 2 LAST CDS_LOCATION C60
J 0
(150 975);
DISPLAY 1.021277 (150 975);
DISPLAY INVISIBLE (150 975);
FORCEPROP 2 LAST $SEC 1
J 0
(150 975);
DISPLAY 0.680851 (150 975);
PAINT MONO (150 975);
DISPLAY INVISIBLE (150 975);
FORCEPROP 2 LAST CDS_SEC 1
J 0
(150 975);
DISPLAY 1.021277 (150 975);
DISPLAY INVISIBLE (150 975);
FORCEADD VCC_CORE..1
(100 1100);
FORCEPROP 3 LASTPIN (100 1050) SIG_NAME P12V_S3_AUX_CPU1_NVDIMM\g
J 0
(110 1060);
DISPLAY 0.659574 (110 1060);
PAINT MONO (110 1060);
DISPLAY INVISIBLE (110 1060);
FORCEPROP 1 LAST HDL_POWER P12V_S3_AUX_CPU1_NVDIMM
J 1
(100 1150);
DISPLAY 1.148936 (100 1150);
PAINT GREEN (100 1150);
FORCEPROP 2 LAST CDS_LIB logical_power
J 0
(100 1100);
PAINT MONO (100 1100);
DISPLAY INVISIBLE (100 1100);
FORCEPROP 1 LAST PATH I126
J 0
(150 1125);
DISPLAY 0.872340 (150 1125);
PAINT AQUA (150 1125);
DISPLAY INVISIBLE (150 1125);
FORCEADD Q_CAP..1
(725 775);
FORCEPROP 1 LAST PART_NUMBER CH6103KEA00
J 0
(775 625);
DISPLAY 0.978723 (775 625);
DISPLAY INVISIBLE (775 625);
FORCEPROP 1 LAST TOLERANCE 10%
J 0
(775 725);
DISPLAY 0.978723 (775 725);
FORCEPROP 1 LAST VALUE 10UF
J 0
(775 825);
DISPLAY 0.978723 (775 825);
FORCEPROP 1 LAST PACK_TYPE C0805
J 0
(775 575);
DISPLAY 0.978723 (775 575);
FORCEPROP 1 LAST VOLTAGE 16V
J 0
(775 775);
DISPLAY 0.978723 (775 775);
FORCEPROP 1 LAST MATERIAL X6S
J 0
(775 675);
DISPLAY 0.978723 (775 675);
FORCEPROP 1 LAST $LOCATION C61
J 0
(775 875);
DISPLAY 0.978723 (775 875);
FORCEPROP 1 LASTPIN (725 875) $PN 1
J 0
(735 855);
DISPLAY 0.787234 (735 855);
FORCEPROP 1 LASTPIN (725 675) $PN 2
J 0
(735 655);
DISPLAY 0.787234 (735 655);
FORCEPROP 2 LAST CDS_LIB pure_quanta
J 0
(725 775);
PAINT MONO (725 775);
DISPLAY INVISIBLE (725 775);
FORCEPROP 1 LAST PATH I127
J 0
(775 925);
DISPLAY 0.978723 (775 925);
PAINT WHITE (775 925);
DISPLAY INVISIBLE (775 925);
FORCEPROP 2 LAST CDS_LOCATION C61
J 0
(775 975);
DISPLAY 1.021277 (775 975);
DISPLAY INVISIBLE (775 975);
FORCEPROP 2 LAST $SEC 1
J 0
(775 975);
DISPLAY 0.680851 (775 975);
PAINT MONO (775 975);
DISPLAY INVISIBLE (775 975);
FORCEPROP 2 LAST CDS_SEC 1
J 0
(775 975);
DISPLAY 1.021277 (775 975);
DISPLAY INVISIBLE (775 975);
FORCEADD UNIVERSAL_GND..1
(725 400);
FORCEPROP 3 LASTPIN (725 450) SIG_NAME GND\g
J 0
(735 460);
DISPLAY 0.659574 (735 460);
PAINT MONO (735 460);
DISPLAY INVISIBLE (735 460);
FORCEPROP 1 LAST PATH I128
J 0
(800 400);
DISPLAY 0.872340 (800 400);
PAINT AQUA (800 400);
DISPLAY INVISIBLE (800 400);
FORCEPROP 1 LAST HDL_POWER GND
J 1
(750 325);
DISPLAY 0.872340 (750 325);
PAINT GREEN (750 325);
DISPLAY INVISIBLE (750 325);
FORCEPROP 2 LAST CDS_LIB logical_power
J 0
(725 400);
PAINT MONO (725 400);
DISPLAY INVISIBLE (725 400);
FORCEADD UNIVERSAL_GND..1
(1800 950);
FORCEPROP 3 LASTPIN (1800 1000) SIG_NAME GND\g
J 0
(1810 1010);
DISPLAY 0.659574 (1810 1010);
PAINT MONO (1810 1010);
DISPLAY INVISIBLE (1810 1010);
FORCEPROP 1 LAST PATH I129
J 0
(1875 950);
DISPLAY 0.872340 (1875 950);
PAINT AQUA (1875 950);
DISPLAY INVISIBLE (1875 950);
FORCEPROP 1 LAST HDL_POWER GND
J 1
(1825 875);
DISPLAY 0.872340 (1825 875);
PAINT GREEN (1825 875);
DISPLAY INVISIBLE (1825 875);
FORCEPROP 2 LAST CDS_LIB logical_power
J 0
(1800 950);
PAINT MONO (1800 950);
DISPLAY INVISIBLE (1800 950);
FORCEADD OFFPAGE..1
(-5200 3550);
FORCEPROP 2 LAST $XR0 52 
J 0
(-5421 3550);
DISPLAY 0.638298 (-5421 3550);
PAINT MONO (-5421 3550);
FORCEPROP 2 LAST CDS_LIB standard
J 0
(-5200 3550);
PAINT MONO (-5200 3550);
DISPLAY INVISIBLE (-5200 3550);
FORCEPROP 1 LAST OFFPAGE TRUE
J 0
(-4875 3425);
DISPLAY 0.872340 (-4875 3425);
DISPLAY INVISIBLE (-4875 3425);
FORCEPROP 1 LAST COMMENT_BODY TRUE
J 0
(-5075 3450);
DISPLAY 0.872340 (-5075 3450);
PAINT GREEN (-5075 3450);
DISPLAY INVISIBLE (-5075 3450);
FORCEPROP 2 LAST PATH I13
J 0
(-5150 3625);
DISPLAY 1.021277 (-5150 3625);
DISPLAY INVISIBLE (-5150 3625);
FORCEADD TAP..1
(125 2700);
FORCEPROP 3 LASTPIN (75 2700) SIG_NAME M_B_CPU1_SB_DQS_DP<0>
J 0
(85 2710);
DISPLAY 0.659574 (85 2710);
PAINT MONO (85 2710);
DISPLAY INVISIBLE (85 2710);
FORCEPROP 1 LASTPIN (75 2700) BN 0
J 0
(63 2708);
DISPLAY 0.680851 (63 2708);
PAINT GREEN (63 2708);
FORCEPROP 2 LAST CDS_LIB standard
J 0
(125 2700);
PAINT MONO (125 2700);
DISPLAY INVISIBLE (125 2700);
FORCEPROP 1 LAST BODY_TYPE PLUMBING
J 0
(125 2750);
DISPLAY 0.872340 (125 2750);
PAINT GREEN (125 2750);
DISPLAY INVISIBLE (125 2750);
FORCEPROP 1 LAST HDL_TAP TRUE
J 0
(450 2575);
DISPLAY 0.872340 (450 2575);
DISPLAY INVISIBLE (450 2575);
FORCEPROP 1 LAST PATH I130
J 0
(123 2700);
DISPLAY 0.872340 (123 2700);
PAINT GREEN (123 2700);
DISPLAY INVISIBLE (123 2700);
FORCEADD TAP..1
(125 2800);
FORCEPROP 3 LASTPIN (75 2800) SIG_NAME M_B_CPU1_SB_DQS_DP<1>
J 0
(85 2810);
DISPLAY 0.659574 (85 2810);
PAINT MONO (85 2810);
DISPLAY INVISIBLE (85 2810);
FORCEPROP 1 LASTPIN (75 2800) BN 1
J 0
(63 2808);
DISPLAY 0.680851 (63 2808);
PAINT GREEN (63 2808);
FORCEPROP 2 LAST CDS_LIB standard
J 0
(125 2800);
DISPLAY INVISIBLE (125 2800);
FORCEPROP 1 LAST BODY_TYPE PLUMBING
J 0
(125 2850);
DISPLAY 0.872340 (125 2850);
PAINT GREEN (125 2850);
DISPLAY INVISIBLE (125 2850);
FORCEPROP 1 LAST HDL_TAP TRUE
J 0
(450 2675);
DISPLAY 0.872340 (450 2675);
DISPLAY INVISIBLE (450 2675);
FORCEPROP 1 LAST PATH I131
J 0
(123 2800);
DISPLAY 0.872340 (123 2800);
PAINT GREEN (123 2800);
DISPLAY INVISIBLE (123 2800);
FORCEADD TAP..1
(300 2750);
FORCEPROP 3 LASTPIN (250 2750) SIG_NAME M_B_CPU1_SB_DQS_DN<1>
J 0
(260 2760);
DISPLAY 0.659574 (260 2760);
PAINT MONO (260 2760);
DISPLAY INVISIBLE (260 2760);
FORCEPROP 1 LASTPIN (250 2750) BN 1
J 0
(238 2758);
DISPLAY 0.680851 (238 2758);
PAINT GREEN (238 2758);
FORCEPROP 2 LAST CDS_LIB standard
J 0
(300 2750);
DISPLAY INVISIBLE (300 2750);
FORCEPROP 1 LAST BODY_TYPE PLUMBING
J 0
(300 2800);
DISPLAY 0.872340 (300 2800);
PAINT GREEN (300 2800);
DISPLAY INVISIBLE (300 2800);
FORCEPROP 1 LAST HDL_TAP TRUE
J 0
(625 2625);
DISPLAY 0.872340 (625 2625);
DISPLAY INVISIBLE (625 2625);
FORCEPROP 1 LAST PATH I132
J 0
(298 2750);
DISPLAY 0.872340 (298 2750);
PAINT GREEN (298 2750);
DISPLAY INVISIBLE (298 2750);
FORCEADD TAP..1
(300 2650);
FORCEPROP 3 LASTPIN (250 2650) SIG_NAME M_B_CPU1_SB_DQS_DN<0>
J 0
(260 2660);
DISPLAY 0.659574 (260 2660);
PAINT MONO (260 2660);
DISPLAY INVISIBLE (260 2660);
FORCEPROP 1 LASTPIN (250 2650) BN 0
J 0
(238 2658);
DISPLAY 0.680851 (238 2658);
PAINT GREEN (238 2658);
FORCEPROP 2 LAST CDS_LIB standard
J 0
(300 2650);
PAINT MONO (300 2650);
DISPLAY INVISIBLE (300 2650);
FORCEPROP 1 LAST BODY_TYPE PLUMBING
J 0
(300 2700);
DISPLAY 0.872340 (300 2700);
PAINT GREEN (300 2700);
DISPLAY INVISIBLE (300 2700);
FORCEPROP 1 LAST HDL_TAP TRUE
J 0
(625 2525);
DISPLAY 0.872340 (625 2525);
DISPLAY INVISIBLE (625 2525);
FORCEPROP 1 LAST PATH I133
J 0
(298 2650);
DISPLAY 0.872340 (298 2650);
PAINT GREEN (298 2650);
DISPLAY INVISIBLE (298 2650);
FORCEADD TAP..1
(125 2900);
FORCEPROP 3 LASTPIN (75 2900) SIG_NAME M_B_CPU1_SB_DQS_DP<2>
J 0
(85 2910);
DISPLAY 0.659574 (85 2910);
PAINT MONO (85 2910);
DISPLAY INVISIBLE (85 2910);
FORCEPROP 1 LASTPIN (75 2900) BN 2
J 0
(63 2908);
DISPLAY 0.680851 (63 2908);
PAINT GREEN (63 2908);
FORCEPROP 2 LAST CDS_LIB standard
J 0
(125 2900);
DISPLAY INVISIBLE (125 2900);
FORCEPROP 1 LAST BODY_TYPE PLUMBING
J 0
(125 2950);
DISPLAY 0.872340 (125 2950);
PAINT GREEN (125 2950);
DISPLAY INVISIBLE (125 2950);
FORCEPROP 1 LAST HDL_TAP TRUE
J 0
(450 2775);
DISPLAY 0.872340 (450 2775);
DISPLAY INVISIBLE (450 2775);
FORCEPROP 1 LAST PATH I134
J 0
(123 2900);
DISPLAY 0.872340 (123 2900);
PAINT GREEN (123 2900);
DISPLAY INVISIBLE (123 2900);
FORCEADD TAP..1
(125 3000);
FORCEPROP 3 LASTPIN (75 3000) SIG_NAME M_B_CPU1_SB_DQS_DP<3>
J 0
(85 3010);
DISPLAY 0.659574 (85 3010);
PAINT MONO (85 3010);
DISPLAY INVISIBLE (85 3010);
FORCEPROP 1 LASTPIN (75 3000) BN 3
J 0
(63 3008);
DISPLAY 0.680851 (63 3008);
PAINT GREEN (63 3008);
FORCEPROP 2 LAST CDS_LIB standard
J 0
(125 3000);
PAINT MONO (125 3000);
DISPLAY INVISIBLE (125 3000);
FORCEPROP 1 LAST BODY_TYPE PLUMBING
J 0
(125 3050);
DISPLAY 0.872340 (125 3050);
PAINT GREEN (125 3050);
DISPLAY INVISIBLE (125 3050);
FORCEPROP 1 LAST HDL_TAP TRUE
J 0
(450 2875);
DISPLAY 0.872340 (450 2875);
DISPLAY INVISIBLE (450 2875);
FORCEPROP 1 LAST PATH I135
J 0
(123 3000);
DISPLAY 0.872340 (123 3000);
PAINT GREEN (123 3000);
DISPLAY INVISIBLE (123 3000);
FORCEADD TAP..1
(300 2850);
FORCEPROP 3 LASTPIN (250 2850) SIG_NAME M_B_CPU1_SB_DQS_DN<2>
J 0
(260 2860);
DISPLAY 0.659574 (260 2860);
PAINT MONO (260 2860);
DISPLAY INVISIBLE (260 2860);
FORCEPROP 1 LASTPIN (250 2850) BN 2
J 0
(238 2858);
DISPLAY 0.680851 (238 2858);
PAINT GREEN (238 2858);
FORCEPROP 2 LAST CDS_LIB standard
J 0
(300 2850);
DISPLAY INVISIBLE (300 2850);
FORCEPROP 1 LAST BODY_TYPE PLUMBING
J 0
(300 2900);
DISPLAY 0.872340 (300 2900);
PAINT GREEN (300 2900);
DISPLAY INVISIBLE (300 2900);
FORCEPROP 1 LAST HDL_TAP TRUE
J 0
(625 2725);
DISPLAY 0.872340 (625 2725);
DISPLAY INVISIBLE (625 2725);
FORCEPROP 1 LAST PATH I136
J 0
(298 2850);
DISPLAY 0.872340 (298 2850);
PAINT GREEN (298 2850);
DISPLAY INVISIBLE (298 2850);
FORCEADD TAP..1
(300 3050);
FORCEPROP 3 LASTPIN (250 3050) SIG_NAME M_B_CPU1_SB_DQS_DN<4>
J 0
(260 3060);
DISPLAY 0.659574 (260 3060);
PAINT MONO (260 3060);
DISPLAY INVISIBLE (260 3060);
FORCEPROP 1 LASTPIN (250 3050) BN 4
J 0
(238 3058);
DISPLAY 0.680851 (238 3058);
PAINT GREEN (238 3058);
FORCEPROP 2 LAST CDS_LIB standard
J 0
(300 3050);
PAINT MONO (300 3050);
DISPLAY INVISIBLE (300 3050);
FORCEPROP 1 LAST BODY_TYPE PLUMBING
J 0
(300 3100);
DISPLAY 0.872340 (300 3100);
PAINT GREEN (300 3100);
DISPLAY INVISIBLE (300 3100);
FORCEPROP 1 LAST HDL_TAP TRUE
J 0
(625 2925);
DISPLAY 0.872340 (625 2925);
DISPLAY INVISIBLE (625 2925);
FORCEPROP 1 LAST PATH I137
J 0
(298 3050);
DISPLAY 0.872340 (298 3050);
PAINT GREEN (298 3050);
DISPLAY INVISIBLE (298 3050);
FORCEADD TAP..1
(300 2950);
FORCEPROP 3 LASTPIN (250 2950) SIG_NAME M_B_CPU1_SB_DQS_DN<3>
J 0
(260 2960);
DISPLAY 0.659574 (260 2960);
PAINT MONO (260 2960);
DISPLAY INVISIBLE (260 2960);
FORCEPROP 1 LASTPIN (250 2950) BN 3
J 0
(238 2958);
DISPLAY 0.680851 (238 2958);
PAINT GREEN (238 2958);
FORCEPROP 2 LAST CDS_LIB standard
J 0
(300 2950);
PAINT MONO (300 2950);
DISPLAY INVISIBLE (300 2950);
FORCEPROP 1 LAST BODY_TYPE PLUMBING
J 0
(300 3000);
DISPLAY 0.872340 (300 3000);
PAINT GREEN (300 3000);
DISPLAY INVISIBLE (300 3000);
FORCEPROP 1 LAST HDL_TAP TRUE
J 0
(625 2825);
DISPLAY 0.872340 (625 2825);
DISPLAY INVISIBLE (625 2825);
FORCEPROP 1 LAST PATH I138
J 0
(298 2950);
DISPLAY 0.872340 (298 2950);
PAINT GREEN (298 2950);
DISPLAY INVISIBLE (298 2950);
FORCEADD TAP..1
(125 3100);
FORCEPROP 3 LASTPIN (75 3100) SIG_NAME M_B_CPU1_SB_DQS_DP<4>
J 0
(85 3110);
DISPLAY 0.659574 (85 3110);
PAINT MONO (85 3110);
DISPLAY INVISIBLE (85 3110);
FORCEPROP 1 LASTPIN (75 3100) BN 4
J 0
(63 3108);
DISPLAY 0.680851 (63 3108);
PAINT GREEN (63 3108);
FORCEPROP 2 LAST CDS_LIB standard
J 0
(125 3100);
PAINT MONO (125 3100);
DISPLAY INVISIBLE (125 3100);
FORCEPROP 1 LAST BODY_TYPE PLUMBING
J 0
(125 3150);
DISPLAY 0.872340 (125 3150);
PAINT GREEN (125 3150);
DISPLAY INVISIBLE (125 3150);
FORCEPROP 1 LAST HDL_TAP TRUE
J 0
(450 2975);
DISPLAY 0.872340 (450 2975);
DISPLAY INVISIBLE (450 2975);
FORCEPROP 1 LAST PATH I139
J 0
(123 3100);
DISPLAY 0.872340 (123 3100);
PAINT GREEN (123 3100);
DISPLAY INVISIBLE (123 3100);
FORCEADD OFFPAGE..1
(-5200 3500);
FORCEPROP 2 LAST $XR0 52 
J 0
(-5421 3500);
DISPLAY 0.638298 (-5421 3500);
PAINT MONO (-5421 3500);
FORCEPROP 2 LAST CDS_LIB standard
J 0
(-5200 3500);
PAINT MONO (-5200 3500);
DISPLAY INVISIBLE (-5200 3500);
FORCEPROP 1 LAST OFFPAGE TRUE
J 0
(-4875 3375);
DISPLAY 0.872340 (-4875 3375);
DISPLAY INVISIBLE (-4875 3375);
FORCEPROP 1 LAST COMMENT_BODY TRUE
J 0
(-5075 3400);
DISPLAY 0.872340 (-5075 3400);
PAINT GREEN (-5075 3400);
DISPLAY INVISIBLE (-5075 3400);
FORCEPROP 2 LAST PATH I14
J 0
(-5150 3575);
DISPLAY 1.021277 (-5150 3575);
DISPLAY INVISIBLE (-5150 3575);
FORCEADD TAP..1
(125 3200);
FORCEPROP 3 LASTPIN (75 3200) SIG_NAME M_B_CPU1_SB_DQS_DP<5>
J 0
(85 3210);
DISPLAY 0.659574 (85 3210);
PAINT MONO (85 3210);
DISPLAY INVISIBLE (85 3210);
FORCEPROP 1 LASTPIN (75 3200) BN 5
J 0
(63 3208);
DISPLAY 0.680851 (63 3208);
PAINT GREEN (63 3208);
FORCEPROP 2 LAST CDS_LIB standard
J 0
(125 3200);
DISPLAY INVISIBLE (125 3200);
FORCEPROP 1 LAST BODY_TYPE PLUMBING
J 0
(125 3250);
DISPLAY 0.872340 (125 3250);
PAINT GREEN (125 3250);
DISPLAY INVISIBLE (125 3250);
FORCEPROP 1 LAST HDL_TAP TRUE
J 0
(450 3075);
DISPLAY 0.872340 (450 3075);
DISPLAY INVISIBLE (450 3075);
FORCEPROP 1 LAST PATH I140
J 0
(123 3200);
DISPLAY 0.872340 (123 3200);
PAINT GREEN (123 3200);
DISPLAY INVISIBLE (123 3200);
FORCEADD TAP..1
(125 3300);
FORCEPROP 3 LASTPIN (75 3300) SIG_NAME M_B_CPU1_SB_DQS_DP<6>
J 0
(85 3310);
DISPLAY 0.659574 (85 3310);
PAINT MONO (85 3310);
DISPLAY INVISIBLE (85 3310);
FORCEPROP 1 LASTPIN (75 3300) BN 6
J 0
(63 3308);
DISPLAY 0.680851 (63 3308);
PAINT GREEN (63 3308);
FORCEPROP 2 LAST CDS_LIB standard
J 0
(125 3300);
DISPLAY INVISIBLE (125 3300);
FORCEPROP 1 LAST BODY_TYPE PLUMBING
J 0
(125 3350);
DISPLAY 0.872340 (125 3350);
PAINT GREEN (125 3350);
DISPLAY INVISIBLE (125 3350);
FORCEPROP 1 LAST HDL_TAP TRUE
J 0
(450 3175);
DISPLAY 0.872340 (450 3175);
DISPLAY INVISIBLE (450 3175);
FORCEPROP 1 LAST PATH I141
J 0
(123 3300);
DISPLAY 0.872340 (123 3300);
PAINT GREEN (123 3300);
DISPLAY INVISIBLE (123 3300);
FORCEADD TAP..1
(300 3150);
FORCEPROP 3 LASTPIN (250 3150) SIG_NAME M_B_CPU1_SB_DQS_DN<5>
J 0
(260 3160);
DISPLAY 0.659574 (260 3160);
PAINT MONO (260 3160);
DISPLAY INVISIBLE (260 3160);
FORCEPROP 1 LASTPIN (250 3150) BN 5
J 0
(238 3158);
DISPLAY 0.680851 (238 3158);
PAINT GREEN (238 3158);
FORCEPROP 2 LAST CDS_LIB standard
J 0
(300 3150);
DISPLAY INVISIBLE (300 3150);
FORCEPROP 1 LAST BODY_TYPE PLUMBING
J 0
(300 3200);
DISPLAY 0.872340 (300 3200);
PAINT GREEN (300 3200);
DISPLAY INVISIBLE (300 3200);
FORCEPROP 1 LAST HDL_TAP TRUE
J 0
(625 3025);
DISPLAY 0.872340 (625 3025);
DISPLAY INVISIBLE (625 3025);
FORCEPROP 1 LAST PATH I142
J 0
(298 3150);
DISPLAY 0.872340 (298 3150);
PAINT GREEN (298 3150);
DISPLAY INVISIBLE (298 3150);
FORCEADD TAP..1
(300 3250);
FORCEPROP 3 LASTPIN (250 3250) SIG_NAME M_B_CPU1_SB_DQS_DN<6>
J 0
(260 3260);
DISPLAY 0.659574 (260 3260);
PAINT MONO (260 3260);
DISPLAY INVISIBLE (260 3260);
FORCEPROP 1 LASTPIN (250 3250) BN 6
J 0
(238 3258);
DISPLAY 0.680851 (238 3258);
PAINT GREEN (238 3258);
FORCEPROP 2 LAST CDS_LIB standard
J 0
(300 3250);
DISPLAY INVISIBLE (300 3250);
FORCEPROP 1 LAST BODY_TYPE PLUMBING
J 0
(300 3300);
DISPLAY 0.872340 (300 3300);
PAINT GREEN (300 3300);
DISPLAY INVISIBLE (300 3300);
FORCEPROP 1 LAST HDL_TAP TRUE
J 0
(625 3125);
DISPLAY 0.872340 (625 3125);
DISPLAY INVISIBLE (625 3125);
FORCEPROP 1 LAST PATH I143
J 0
(298 3250);
DISPLAY 0.872340 (298 3250);
PAINT GREEN (298 3250);
DISPLAY INVISIBLE (298 3250);
FORCEADD TAP..1
(125 3400);
FORCEPROP 3 LASTPIN (75 3400) SIG_NAME M_B_CPU1_SB_DQS_DP<7>
J 0
(85 3410);
DISPLAY 0.659574 (85 3410);
PAINT MONO (85 3410);
DISPLAY INVISIBLE (85 3410);
FORCEPROP 1 LASTPIN (75 3400) BN 7
J 0
(63 3408);
DISPLAY 0.680851 (63 3408);
PAINT GREEN (63 3408);
FORCEPROP 2 LAST CDS_LIB standard
J 0
(125 3400);
DISPLAY INVISIBLE (125 3400);
FORCEPROP 1 LAST BODY_TYPE PLUMBING
J 0
(125 3450);
DISPLAY 0.872340 (125 3450);
PAINT GREEN (125 3450);
DISPLAY INVISIBLE (125 3450);
FORCEPROP 1 LAST HDL_TAP TRUE
J 0
(450 3275);
DISPLAY 0.872340 (450 3275);
DISPLAY INVISIBLE (450 3275);
FORCEPROP 1 LAST PATH I144
J 0
(123 3400);
DISPLAY 0.872340 (123 3400);
PAINT GREEN (123 3400);
DISPLAY INVISIBLE (123 3400);
FORCEADD TAP..1
(125 3500);
FORCEPROP 3 LASTPIN (75 3500) SIG_NAME M_B_CPU1_SB_DQS_DP<8>
J 0
(85 3510);
DISPLAY 0.659574 (85 3510);
PAINT MONO (85 3510);
DISPLAY INVISIBLE (85 3510);
FORCEPROP 1 LASTPIN (75 3500) BN 8
J 0
(63 3508);
DISPLAY 0.680851 (63 3508);
PAINT GREEN (63 3508);
FORCEPROP 2 LAST CDS_LIB standard
J 0
(125 3500);
DISPLAY INVISIBLE (125 3500);
FORCEPROP 1 LAST BODY_TYPE PLUMBING
J 0
(125 3550);
DISPLAY 0.872340 (125 3550);
PAINT GREEN (125 3550);
DISPLAY INVISIBLE (125 3550);
FORCEPROP 1 LAST HDL_TAP TRUE
J 0
(450 3375);
DISPLAY 0.872340 (450 3375);
DISPLAY INVISIBLE (450 3375);
FORCEPROP 1 LAST PATH I145
J 0
(123 3500);
DISPLAY 0.872340 (123 3500);
PAINT GREEN (123 3500);
DISPLAY INVISIBLE (123 3500);
FORCEADD TAP..1
(300 3350);
FORCEPROP 3 LASTPIN (250 3350) SIG_NAME M_B_CPU1_SB_DQS_DN<7>
J 0
(260 3360);
DISPLAY 0.659574 (260 3360);
PAINT MONO (260 3360);
DISPLAY INVISIBLE (260 3360);
FORCEPROP 1 LASTPIN (250 3350) BN 7
J 0
(238 3358);
DISPLAY 0.680851 (238 3358);
PAINT GREEN (238 3358);
FORCEPROP 2 LAST CDS_LIB standard
J 0
(300 3350);
DISPLAY INVISIBLE (300 3350);
FORCEPROP 1 LAST BODY_TYPE PLUMBING
J 0
(300 3400);
DISPLAY 0.872340 (300 3400);
PAINT GREEN (300 3400);
DISPLAY INVISIBLE (300 3400);
FORCEPROP 1 LAST HDL_TAP TRUE
J 0
(625 3225);
DISPLAY 0.872340 (625 3225);
DISPLAY INVISIBLE (625 3225);
FORCEPROP 1 LAST PATH I146
J 0
(298 3350);
DISPLAY 0.872340 (298 3350);
PAINT GREEN (298 3350);
DISPLAY INVISIBLE (298 3350);
FORCEADD TAP..1
(300 3450);
FORCEPROP 3 LASTPIN (250 3450) SIG_NAME M_B_CPU1_SB_DQS_DN<8>
J 0
(260 3460);
DISPLAY 0.659574 (260 3460);
PAINT MONO (260 3460);
DISPLAY INVISIBLE (260 3460);
FORCEPROP 1 LASTPIN (250 3450) BN 8
J 0
(238 3458);
DISPLAY 0.680851 (238 3458);
PAINT GREEN (238 3458);
FORCEPROP 2 LAST CDS_LIB standard
J 0
(300 3450);
DISPLAY INVISIBLE (300 3450);
FORCEPROP 1 LAST BODY_TYPE PLUMBING
J 0
(300 3500);
DISPLAY 0.872340 (300 3500);
PAINT GREEN (300 3500);
DISPLAY INVISIBLE (300 3500);
FORCEPROP 1 LAST HDL_TAP TRUE
J 0
(625 3325);
DISPLAY 0.872340 (625 3325);
DISPLAY INVISIBLE (625 3325);
FORCEPROP 1 LAST PATH I147
J 0
(298 3450);
DISPLAY 0.872340 (298 3450);
PAINT GREEN (298 3450);
DISPLAY INVISIBLE (298 3450);
FORCEADD TAP..1
(300 3550);
FORCEPROP 3 LASTPIN (250 3550) SIG_NAME M_B_CPU1_SB_DQS_DN<9>
J 0
(260 3560);
DISPLAY 0.659574 (260 3560);
PAINT MONO (260 3560);
DISPLAY INVISIBLE (260 3560);
FORCEPROP 1 LASTPIN (250 3550) BN 9
J 0
(238 3558);
DISPLAY 0.680851 (238 3558);
PAINT GREEN (238 3558);
FORCEPROP 2 LAST CDS_LIB standard
J 0
(300 3550);
DISPLAY INVISIBLE (300 3550);
FORCEPROP 1 LAST BODY_TYPE PLUMBING
J 0
(300 3600);
DISPLAY 0.872340 (300 3600);
PAINT GREEN (300 3600);
DISPLAY INVISIBLE (300 3600);
FORCEPROP 1 LAST HDL_TAP TRUE
J 0
(625 3425);
DISPLAY 0.872340 (625 3425);
DISPLAY INVISIBLE (625 3425);
FORCEPROP 1 LAST PATH I148
J 0
(298 3550);
DISPLAY 0.872340 (298 3550);
PAINT GREEN (298 3550);
DISPLAY INVISIBLE (298 3550);
FORCEADD TAP..1
(125 3600);
FORCEPROP 3 LASTPIN (75 3600) SIG_NAME M_B_CPU1_SB_DQS_DP<9>
J 0
(85 3610);
DISPLAY 0.659574 (85 3610);
PAINT MONO (85 3610);
DISPLAY INVISIBLE (85 3610);
FORCEPROP 1 LASTPIN (75 3600) BN 9
J 0
(63 3608);
DISPLAY 0.680851 (63 3608);
PAINT GREEN (63 3608);
FORCEPROP 2 LAST CDS_LIB standard
J 0
(125 3600);
DISPLAY INVISIBLE (125 3600);
FORCEPROP 1 LAST BODY_TYPE PLUMBING
J 0
(125 3650);
DISPLAY 0.872340 (125 3650);
PAINT GREEN (125 3650);
DISPLAY INVISIBLE (125 3650);
FORCEPROP 1 LAST HDL_TAP TRUE
J 0
(450 3475);
DISPLAY 0.872340 (450 3475);
DISPLAY INVISIBLE (450 3475);
FORCEPROP 1 LAST PATH I149
J 0
(123 3600);
DISPLAY 0.872340 (123 3600);
PAINT GREEN (123 3600);
DISPLAY INVISIBLE (123 3600);
FORCEADD OFFPAGE..1
(-5200 3400);
FORCEPROP 2 LAST $XR0 52 
J 0
(-5421 3400);
DISPLAY 0.638298 (-5421 3400);
PAINT MONO (-5421 3400);
FORCEPROP 2 LAST CDS_LIB standard
J 0
(-5200 3400);
PAINT MONO (-5200 3400);
DISPLAY INVISIBLE (-5200 3400);
FORCEPROP 1 LAST OFFPAGE TRUE
J 0
(-4875 3275);
DISPLAY 0.872340 (-4875 3275);
DISPLAY INVISIBLE (-4875 3275);
FORCEPROP 1 LAST COMMENT_BODY TRUE
J 0
(-5075 3300);
DISPLAY 0.872340 (-5075 3300);
PAINT GREEN (-5075 3300);
DISPLAY INVISIBLE (-5075 3300);
FORCEPROP 2 LAST PATH I15
J 0
(-5150 3475);
DISPLAY 1.021277 (-5150 3475);
DISPLAY INVISIBLE (-5150 3475);
FORCEADD TAP..1
(125 3750);
FORCEPROP 3 LASTPIN (75 3750) SIG_NAME M_B_CPU1_SA_DQS_DP<0>
J 0
(85 3760);
DISPLAY 0.659574 (85 3760);
PAINT MONO (85 3760);
DISPLAY INVISIBLE (85 3760);
FORCEPROP 1 LASTPIN (75 3750) BN 0
J 0
(63 3758);
DISPLAY 0.680851 (63 3758);
PAINT GREEN (63 3758);
FORCEPROP 2 LAST CDS_LIB standard
J 0
(125 3750);
PAINT MONO (125 3750);
DISPLAY INVISIBLE (125 3750);
FORCEPROP 1 LAST BODY_TYPE PLUMBING
J 0
(125 3800);
DISPLAY 0.872340 (125 3800);
PAINT GREEN (125 3800);
DISPLAY INVISIBLE (125 3800);
FORCEPROP 1 LAST HDL_TAP TRUE
J 0
(450 3625);
DISPLAY 0.872340 (450 3625);
DISPLAY INVISIBLE (450 3625);
FORCEPROP 1 LAST PATH I150
J 0
(123 3750);
DISPLAY 0.872340 (123 3750);
PAINT GREEN (123 3750);
DISPLAY INVISIBLE (123 3750);
FORCEADD TAP..1
(300 3800);
FORCEPROP 3 LASTPIN (250 3800) SIG_NAME M_B_CPU1_SA_DQS_DN<1>
J 0
(260 3810);
DISPLAY 0.659574 (260 3810);
PAINT MONO (260 3810);
DISPLAY INVISIBLE (260 3810);
FORCEPROP 1 LASTPIN (250 3800) BN 1
J 0
(238 3808);
DISPLAY 0.680851 (238 3808);
PAINT GREEN (238 3808);
FORCEPROP 2 LAST CDS_LIB standard
J 0
(300 3800);
DISPLAY INVISIBLE (300 3800);
FORCEPROP 1 LAST BODY_TYPE PLUMBING
J 0
(300 3850);
DISPLAY 0.872340 (300 3850);
PAINT GREEN (300 3850);
DISPLAY INVISIBLE (300 3850);
FORCEPROP 1 LAST HDL_TAP TRUE
J 0
(625 3675);
DISPLAY 0.872340 (625 3675);
DISPLAY INVISIBLE (625 3675);
FORCEPROP 1 LAST PATH I151
J 0
(298 3800);
DISPLAY 0.872340 (298 3800);
PAINT GREEN (298 3800);
DISPLAY INVISIBLE (298 3800);
FORCEADD TAP..1
(300 3700);
FORCEPROP 3 LASTPIN (250 3700) SIG_NAME M_B_CPU1_SA_DQS_DN<0>
J 0
(260 3710);
DISPLAY 0.659574 (260 3710);
PAINT MONO (260 3710);
DISPLAY INVISIBLE (260 3710);
FORCEPROP 1 LASTPIN (250 3700) BN 0
J 0
(238 3708);
DISPLAY 0.680851 (238 3708);
PAINT GREEN (238 3708);
FORCEPROP 2 LAST CDS_LIB standard
J 0
(300 3700);
PAINT MONO (300 3700);
DISPLAY INVISIBLE (300 3700);
FORCEPROP 1 LAST BODY_TYPE PLUMBING
J 0
(300 3750);
DISPLAY 0.872340 (300 3750);
PAINT GREEN (300 3750);
DISPLAY INVISIBLE (300 3750);
FORCEPROP 1 LAST HDL_TAP TRUE
J 0
(625 3575);
DISPLAY 0.872340 (625 3575);
DISPLAY INVISIBLE (625 3575);
FORCEPROP 1 LAST PATH I152
J 0
(298 3700);
DISPLAY 0.872340 (298 3700);
PAINT GREEN (298 3700);
DISPLAY INVISIBLE (298 3700);
FORCEADD TAP..1
(125 3850);
FORCEPROP 3 LASTPIN (75 3850) SIG_NAME M_B_CPU1_SA_DQS_DP<1>
J 0
(85 3860);
DISPLAY 0.659574 (85 3860);
PAINT MONO (85 3860);
DISPLAY INVISIBLE (85 3860);
FORCEPROP 1 LASTPIN (75 3850) BN 1
J 0
(63 3858);
DISPLAY 0.680851 (63 3858);
PAINT GREEN (63 3858);
FORCEPROP 2 LAST CDS_LIB standard
J 0
(125 3850);
DISPLAY INVISIBLE (125 3850);
FORCEPROP 1 LAST BODY_TYPE PLUMBING
J 0
(125 3900);
DISPLAY 0.872340 (125 3900);
PAINT GREEN (125 3900);
DISPLAY INVISIBLE (125 3900);
FORCEPROP 1 LAST HDL_TAP TRUE
J 0
(450 3725);
DISPLAY 0.872340 (450 3725);
DISPLAY INVISIBLE (450 3725);
FORCEPROP 1 LAST PATH I153
J 0
(123 3850);
DISPLAY 0.872340 (123 3850);
PAINT GREEN (123 3850);
DISPLAY INVISIBLE (123 3850);
FORCEADD TAP..1
(125 3950);
FORCEPROP 3 LASTPIN (75 3950) SIG_NAME M_B_CPU1_SA_DQS_DP<2>
J 0
(85 3960);
DISPLAY 0.659574 (85 3960);
PAINT MONO (85 3960);
DISPLAY INVISIBLE (85 3960);
FORCEPROP 1 LASTPIN (75 3950) BN 2
J 0
(63 3958);
DISPLAY 0.680851 (63 3958);
PAINT GREEN (63 3958);
FORCEPROP 2 LAST CDS_LIB standard
J 0
(125 3950);
DISPLAY INVISIBLE (125 3950);
FORCEPROP 1 LAST BODY_TYPE PLUMBING
J 0
(125 4000);
DISPLAY 0.872340 (125 4000);
PAINT GREEN (125 4000);
DISPLAY INVISIBLE (125 4000);
FORCEPROP 1 LAST HDL_TAP TRUE
J 0
(450 3825);
DISPLAY 0.872340 (450 3825);
DISPLAY INVISIBLE (450 3825);
FORCEPROP 1 LAST PATH I154
J 0
(123 3950);
DISPLAY 0.872340 (123 3950);
PAINT GREEN (123 3950);
DISPLAY INVISIBLE (123 3950);
FORCEADD TAP..1
(125 4050);
FORCEPROP 3 LASTPIN (75 4050) SIG_NAME M_B_CPU1_SA_DQS_DP<3>
J 0
(85 4060);
DISPLAY 0.659574 (85 4060);
PAINT MONO (85 4060);
DISPLAY INVISIBLE (85 4060);
FORCEPROP 1 LASTPIN (75 4050) BN 3
J 0
(63 4058);
DISPLAY 0.680851 (63 4058);
PAINT GREEN (63 4058);
FORCEPROP 2 LAST CDS_LIB standard
J 0
(125 4050);
PAINT MONO (125 4050);
DISPLAY INVISIBLE (125 4050);
FORCEPROP 1 LAST BODY_TYPE PLUMBING
J 0
(125 4100);
DISPLAY 0.872340 (125 4100);
PAINT GREEN (125 4100);
DISPLAY INVISIBLE (125 4100);
FORCEPROP 1 LAST HDL_TAP TRUE
J 0
(450 3925);
DISPLAY 0.872340 (450 3925);
DISPLAY INVISIBLE (450 3925);
FORCEPROP 1 LAST PATH I155
J 0
(123 4050);
DISPLAY 0.872340 (123 4050);
PAINT GREEN (123 4050);
DISPLAY INVISIBLE (123 4050);
FORCEADD TAP..1
(300 3900);
FORCEPROP 3 LASTPIN (250 3900) SIG_NAME M_B_CPU1_SA_DQS_DN<2>
J 0
(260 3910);
DISPLAY 0.659574 (260 3910);
PAINT MONO (260 3910);
DISPLAY INVISIBLE (260 3910);
FORCEPROP 1 LASTPIN (250 3900) BN 2
J 0
(238 3908);
DISPLAY 0.680851 (238 3908);
PAINT GREEN (238 3908);
FORCEPROP 2 LAST CDS_LIB standard
J 0
(300 3900);
DISPLAY INVISIBLE (300 3900);
FORCEPROP 1 LAST BODY_TYPE PLUMBING
J 0
(300 3950);
DISPLAY 0.872340 (300 3950);
PAINT GREEN (300 3950);
DISPLAY INVISIBLE (300 3950);
FORCEPROP 1 LAST HDL_TAP TRUE
J 0
(625 3775);
DISPLAY 0.872340 (625 3775);
DISPLAY INVISIBLE (625 3775);
FORCEPROP 1 LAST PATH I156
J 0
(298 3900);
DISPLAY 0.872340 (298 3900);
PAINT GREEN (298 3900);
DISPLAY INVISIBLE (298 3900);
FORCEADD TAP..1
(300 4000);
FORCEPROP 3 LASTPIN (250 4000) SIG_NAME M_B_CPU1_SA_DQS_DN<3>
J 0
(260 4010);
DISPLAY 0.659574 (260 4010);
PAINT MONO (260 4010);
DISPLAY INVISIBLE (260 4010);
FORCEPROP 1 LASTPIN (250 4000) BN 3
J 0
(238 4008);
DISPLAY 0.680851 (238 4008);
PAINT GREEN (238 4008);
FORCEPROP 2 LAST CDS_LIB standard
J 0
(300 4000);
PAINT MONO (300 4000);
DISPLAY INVISIBLE (300 4000);
FORCEPROP 1 LAST BODY_TYPE PLUMBING
J 0
(300 4050);
DISPLAY 0.872340 (300 4050);
PAINT GREEN (300 4050);
DISPLAY INVISIBLE (300 4050);
FORCEPROP 1 LAST HDL_TAP TRUE
J 0
(625 3875);
DISPLAY 0.872340 (625 3875);
DISPLAY INVISIBLE (625 3875);
FORCEPROP 1 LAST PATH I157
J 0
(298 4000);
DISPLAY 0.872340 (298 4000);
PAINT GREEN (298 4000);
DISPLAY INVISIBLE (298 4000);
FORCEADD TAP..1
(125 4150);
FORCEPROP 3 LASTPIN (75 4150) SIG_NAME M_B_CPU1_SA_DQS_DP<4>
J 0
(85 4160);
DISPLAY 0.659574 (85 4160);
PAINT MONO (85 4160);
DISPLAY INVISIBLE (85 4160);
FORCEPROP 1 LASTPIN (75 4150) BN 4
J 0
(63 4158);
DISPLAY 0.680851 (63 4158);
PAINT GREEN (63 4158);
FORCEPROP 2 LAST CDS_LIB standard
J 0
(125 4150);
PAINT MONO (125 4150);
DISPLAY INVISIBLE (125 4150);
FORCEPROP 1 LAST BODY_TYPE PLUMBING
J 0
(125 4200);
DISPLAY 0.872340 (125 4200);
PAINT GREEN (125 4200);
DISPLAY INVISIBLE (125 4200);
FORCEPROP 1 LAST HDL_TAP TRUE
J 0
(450 4025);
DISPLAY 0.872340 (450 4025);
DISPLAY INVISIBLE (450 4025);
FORCEPROP 1 LAST PATH I158
J 0
(123 4150);
DISPLAY 0.872340 (123 4150);
PAINT GREEN (123 4150);
DISPLAY INVISIBLE (123 4150);
FORCEADD TAP..1
(125 4250);
FORCEPROP 3 LASTPIN (75 4250) SIG_NAME M_B_CPU1_SA_DQS_DP<5>
J 0
(85 4260);
DISPLAY 0.659574 (85 4260);
PAINT MONO (85 4260);
DISPLAY INVISIBLE (85 4260);
FORCEPROP 1 LASTPIN (75 4250) BN 5
J 0
(63 4258);
DISPLAY 0.680851 (63 4258);
PAINT GREEN (63 4258);
FORCEPROP 2 LAST CDS_LIB standard
J 0
(125 4250);
DISPLAY INVISIBLE (125 4250);
FORCEPROP 1 LAST BODY_TYPE PLUMBING
J 0
(125 4300);
DISPLAY 0.872340 (125 4300);
PAINT GREEN (125 4300);
DISPLAY INVISIBLE (125 4300);
FORCEPROP 1 LAST HDL_TAP TRUE
J 0
(450 4125);
DISPLAY 0.872340 (450 4125);
DISPLAY INVISIBLE (450 4125);
FORCEPROP 1 LAST PATH I159
J 0
(123 4250);
DISPLAY 0.872340 (123 4250);
PAINT GREEN (123 4250);
DISPLAY INVISIBLE (123 4250);
FORCEADD OFFPAGE..1
(-5200 3800);
FORCEPROP 2 LAST $XR1 100 
J 0
(-5541 3800);
DISPLAY 0.638298 (-5541 3800);
PAINT MONO (-5541 3800);
FORCEPROP 2 LAST $XR0 52 
J 0
(-5421 3800);
DISPLAY 0.638298 (-5421 3800);
PAINT MONO (-5421 3800);
FORCEPROP 2 LAST CDS_LIB standard
J 0
(-5200 3800);
PAINT MONO (-5200 3800);
DISPLAY INVISIBLE (-5200 3800);
FORCEPROP 1 LAST OFFPAGE TRUE
J 0
(-4875 3675);
DISPLAY 0.872340 (-4875 3675);
DISPLAY INVISIBLE (-4875 3675);
FORCEPROP 1 LAST COMMENT_BODY TRUE
J 0
(-5075 3700);
DISPLAY 0.872340 (-5075 3700);
PAINT GREEN (-5075 3700);
DISPLAY INVISIBLE (-5075 3700);
FORCEPROP 2 LAST PATH I16
J 0
(-5150 3875);
DISPLAY 1.021277 (-5150 3875);
DISPLAY INVISIBLE (-5150 3875);
FORCEADD TAP..1
(300 4300);
FORCEPROP 3 LASTPIN (250 4300) SIG_NAME M_B_CPU1_SA_DQS_DN<6>
J 0
(260 4310);
DISPLAY 0.659574 (260 4310);
PAINT MONO (260 4310);
DISPLAY INVISIBLE (260 4310);
FORCEPROP 1 LASTPIN (250 4300) BN 6
J 0
(238 4308);
DISPLAY 0.680851 (238 4308);
PAINT GREEN (238 4308);
FORCEPROP 2 LAST CDS_LIB standard
J 0
(300 4300);
DISPLAY INVISIBLE (300 4300);
FORCEPROP 1 LAST BODY_TYPE PLUMBING
J 0
(300 4350);
DISPLAY 0.872340 (300 4350);
PAINT GREEN (300 4350);
DISPLAY INVISIBLE (300 4350);
FORCEPROP 1 LAST HDL_TAP TRUE
J 0
(625 4175);
DISPLAY 0.872340 (625 4175);
DISPLAY INVISIBLE (625 4175);
FORCEPROP 1 LAST PATH I160
J 0
(298 4300);
DISPLAY 0.872340 (298 4300);
PAINT GREEN (298 4300);
DISPLAY INVISIBLE (298 4300);
FORCEADD TAP..1
(300 4200);
FORCEPROP 3 LASTPIN (250 4200) SIG_NAME M_B_CPU1_SA_DQS_DN<5>
J 0
(260 4210);
DISPLAY 0.659574 (260 4210);
PAINT MONO (260 4210);
DISPLAY INVISIBLE (260 4210);
FORCEPROP 1 LASTPIN (250 4200) BN 5
J 0
(238 4208);
DISPLAY 0.680851 (238 4208);
PAINT GREEN (238 4208);
FORCEPROP 2 LAST CDS_LIB standard
J 0
(300 4200);
DISPLAY INVISIBLE (300 4200);
FORCEPROP 1 LAST BODY_TYPE PLUMBING
J 0
(300 4250);
DISPLAY 0.872340 (300 4250);
PAINT GREEN (300 4250);
DISPLAY INVISIBLE (300 4250);
FORCEPROP 1 LAST HDL_TAP TRUE
J 0
(625 4075);
DISPLAY 0.872340 (625 4075);
DISPLAY INVISIBLE (625 4075);
FORCEPROP 1 LAST PATH I161
J 0
(298 4200);
DISPLAY 0.872340 (298 4200);
PAINT GREEN (298 4200);
DISPLAY INVISIBLE (298 4200);
FORCEADD TAP..1
(300 4100);
FORCEPROP 3 LASTPIN (250 4100) SIG_NAME M_B_CPU1_SA_DQS_DN<4>
J 0
(260 4110);
DISPLAY 0.659574 (260 4110);
PAINT MONO (260 4110);
DISPLAY INVISIBLE (260 4110);
FORCEPROP 1 LASTPIN (250 4100) BN 4
J 0
(238 4108);
DISPLAY 0.680851 (238 4108);
PAINT GREEN (238 4108);
FORCEPROP 2 LAST CDS_LIB standard
J 0
(300 4100);
PAINT MONO (300 4100);
DISPLAY INVISIBLE (300 4100);
FORCEPROP 1 LAST BODY_TYPE PLUMBING
J 0
(300 4150);
DISPLAY 0.872340 (300 4150);
PAINT GREEN (300 4150);
DISPLAY INVISIBLE (300 4150);
FORCEPROP 1 LAST HDL_TAP TRUE
J 0
(625 3975);
DISPLAY 0.872340 (625 3975);
DISPLAY INVISIBLE (625 3975);
FORCEPROP 1 LAST PATH I162
J 0
(298 4100);
DISPLAY 0.872340 (298 4100);
PAINT GREEN (298 4100);
DISPLAY INVISIBLE (298 4100);
FORCEADD OFFPAGE..2
(1250 3575);
FORCEPROP 2 LAST $XR1 100 
J 0
(1529 3575);
DISPLAY 0.638298 (1529 3575);
PAINT MONO (1529 3575);
FORCEPROP 2 LAST $XR0 52 
J 0
(1439 3575);
DISPLAY 0.638298 (1439 3575);
PAINT MONO (1439 3575);
FORCEPROP 2 LAST CDS_LIB standard
J 0
(1250 3575);
PAINT MONO (1250 3575);
DISPLAY INVISIBLE (1250 3575);
FORCEPROP 1 LAST OFFPAGE TRUE
J 0
(1575 3450);
DISPLAY 1.170213 (1575 3450);
PAINT GREEN (1575 3450);
DISPLAY INVISIBLE (1575 3450);
FORCEPROP 1 LAST COMMENT_BODY TRUE
J 0
(1205 3480);
DISPLAY 1.170213 (1205 3480);
PAINT GREEN (1205 3480);
DISPLAY INVISIBLE (1205 3480);
FORCEPROP 2 LAST PATH I163
J 0
(1425 3650);
DISPLAY 1.021277 (1425 3650);
DISPLAY INVISIBLE (1425 3650);
FORCEADD OFFPAGE..2
(1250 3625);
FORCEPROP 2 LAST $XR1 100 
J 0
(1529 3625);
DISPLAY 0.638298 (1529 3625);
PAINT MONO (1529 3625);
FORCEPROP 2 LAST $XR0 52 
J 0
(1439 3625);
DISPLAY 0.638298 (1439 3625);
PAINT MONO (1439 3625);
FORCEPROP 2 LAST CDS_LIB standard
J 0
(1250 3625);
PAINT MONO (1250 3625);
DISPLAY INVISIBLE (1250 3625);
FORCEPROP 1 LAST OFFPAGE TRUE
J 0
(1575 3500);
DISPLAY 1.170213 (1575 3500);
PAINT GREEN (1575 3500);
DISPLAY INVISIBLE (1575 3500);
FORCEPROP 1 LAST COMMENT_BODY TRUE
J 0
(1205 3530);
DISPLAY 1.170213 (1205 3530);
PAINT GREEN (1205 3530);
DISPLAY INVISIBLE (1205 3530);
FORCEPROP 2 LAST PATH I164
J 0
(1425 3700);
DISPLAY 1.021277 (1425 3700);
DISPLAY INVISIBLE (1425 3700);
FORCEADD OFFPAGE..3
(-1800 4675);
FORCEPROP 2 LAST $XR1 100 
J 0
(-1496 4675);
DISPLAY 0.638298 (-1496 4675);
PAINT MONO (-1496 4675);
FORCEPROP 2 LAST $XR0 52 
J 0
(-1586 4675);
DISPLAY 0.638298 (-1586 4675);
PAINT MONO (-1586 4675);
FORCEPROP 2 LAST CDS_LIB standard
J 2
(-1800 4675);
DISPLAY INVISIBLE (-1800 4675);
FORCEPROP 1 LAST OFFPAGE TRUE
J 0
(-1475 4550);
DISPLAY 0.872340 (-1475 4550);
DISPLAY INVISIBLE (-1475 4550);
FORCEPROP 1 LAST COMMENT_BODY TRUE
J 0
(-1850 4575);
DISPLAY 0.872340 (-1850 4575);
PAINT GREEN (-1850 4575);
DISPLAY INVISIBLE (-1850 4575);
FORCEPROP 2 LAST PATH I165
J 0
(-1600 4750);
DISPLAY 1.021277 (-1600 4750);
DISPLAY INVISIBLE (-1600 4750);
FORCEADD TAP..1
(125 4350);
FORCEPROP 3 LASTPIN (75 4350) SIG_NAME M_B_CPU1_SA_DQS_DP<6>
J 0
(85 4360);
DISPLAY 0.659574 (85 4360);
PAINT MONO (85 4360);
DISPLAY INVISIBLE (85 4360);
FORCEPROP 1 LASTPIN (75 4350) BN 6
J 0
(63 4358);
DISPLAY 0.680851 (63 4358);
PAINT GREEN (63 4358);
FORCEPROP 2 LAST CDS_LIB standard
J 0
(125 4350);
DISPLAY INVISIBLE (125 4350);
FORCEPROP 1 LAST BODY_TYPE PLUMBING
J 0
(125 4400);
DISPLAY 0.872340 (125 4400);
PAINT GREEN (125 4400);
DISPLAY INVISIBLE (125 4400);
FORCEPROP 1 LAST HDL_TAP TRUE
J 0
(450 4225);
DISPLAY 0.872340 (450 4225);
DISPLAY INVISIBLE (450 4225);
FORCEPROP 1 LAST PATH I166
J 0
(123 4350);
DISPLAY 0.872340 (123 4350);
PAINT GREEN (123 4350);
DISPLAY INVISIBLE (123 4350);
FORCEADD TAP..1
(125 4450);
FORCEPROP 3 LASTPIN (75 4450) SIG_NAME M_B_CPU1_SA_DQS_DP<7>
J 0
(85 4460);
DISPLAY 0.659574 (85 4460);
PAINT MONO (85 4460);
DISPLAY INVISIBLE (85 4460);
FORCEPROP 1 LASTPIN (75 4450) BN 7
J 0
(63 4458);
DISPLAY 0.680851 (63 4458);
PAINT GREEN (63 4458);
FORCEPROP 2 LAST CDS_LIB standard
J 0
(125 4450);
DISPLAY INVISIBLE (125 4450);
FORCEPROP 1 LAST BODY_TYPE PLUMBING
J 0
(125 4500);
DISPLAY 0.872340 (125 4500);
PAINT GREEN (125 4500);
DISPLAY INVISIBLE (125 4500);
FORCEPROP 1 LAST HDL_TAP TRUE
J 0
(450 4325);
DISPLAY 0.872340 (450 4325);
DISPLAY INVISIBLE (450 4325);
FORCEPROP 1 LAST PATH I167
J 0
(123 4450);
DISPLAY 0.872340 (123 4450);
PAINT GREEN (123 4450);
DISPLAY INVISIBLE (123 4450);
FORCEADD TAP..1
(125 4550);
FORCEPROP 3 LASTPIN (75 4550) SIG_NAME M_B_CPU1_SA_DQS_DP<8>
J 0
(85 4560);
DISPLAY 0.659574 (85 4560);
PAINT MONO (85 4560);
DISPLAY INVISIBLE (85 4560);
FORCEPROP 1 LASTPIN (75 4550) BN 8
J 0
(63 4558);
DISPLAY 0.680851 (63 4558);
PAINT GREEN (63 4558);
FORCEPROP 2 LAST CDS_LIB standard
J 0
(125 4550);
DISPLAY INVISIBLE (125 4550);
FORCEPROP 1 LAST BODY_TYPE PLUMBING
J 0
(125 4600);
DISPLAY 0.872340 (125 4600);
PAINT GREEN (125 4600);
DISPLAY INVISIBLE (125 4600);
FORCEPROP 1 LAST HDL_TAP TRUE
J 0
(450 4425);
DISPLAY 0.872340 (450 4425);
DISPLAY INVISIBLE (450 4425);
FORCEPROP 1 LAST PATH I168
J 0
(123 4550);
DISPLAY 0.872340 (123 4550);
PAINT GREEN (123 4550);
DISPLAY INVISIBLE (123 4550);
FORCEADD TAP..1
(300 4400);
FORCEPROP 3 LASTPIN (250 4400) SIG_NAME M_B_CPU1_SA_DQS_DN<7>
J 0
(260 4410);
DISPLAY 0.659574 (260 4410);
PAINT MONO (260 4410);
DISPLAY INVISIBLE (260 4410);
FORCEPROP 1 LASTPIN (250 4400) BN 7
J 0
(238 4408);
DISPLAY 0.680851 (238 4408);
PAINT GREEN (238 4408);
FORCEPROP 2 LAST CDS_LIB standard
J 0
(300 4400);
DISPLAY INVISIBLE (300 4400);
FORCEPROP 1 LAST BODY_TYPE PLUMBING
J 0
(300 4450);
DISPLAY 0.872340 (300 4450);
PAINT GREEN (300 4450);
DISPLAY INVISIBLE (300 4450);
FORCEPROP 1 LAST HDL_TAP TRUE
J 0
(625 4275);
DISPLAY 0.872340 (625 4275);
DISPLAY INVISIBLE (625 4275);
FORCEPROP 1 LAST PATH I169
J 0
(298 4400);
DISPLAY 0.872340 (298 4400);
PAINT GREEN (298 4400);
DISPLAY INVISIBLE (298 4400);
FORCEADD OFFPAGE..1
(-5200 3700);
FORCEPROP 2 LAST $XR0 52 
J 0
(-5421 3700);
DISPLAY 0.638298 (-5421 3700);
PAINT MONO (-5421 3700);
FORCEPROP 2 LAST CDS_LIB standard
J 0
(-5200 3700);
PAINT MONO (-5200 3700);
DISPLAY INVISIBLE (-5200 3700);
FORCEPROP 1 LAST OFFPAGE TRUE
J 0
(-4875 3575);
DISPLAY 0.872340 (-4875 3575);
DISPLAY INVISIBLE (-4875 3575);
FORCEPROP 1 LAST COMMENT_BODY TRUE
J 0
(-5075 3600);
DISPLAY 0.872340 (-5075 3600);
PAINT GREEN (-5075 3600);
DISPLAY INVISIBLE (-5075 3600);
FORCEPROP 2 LAST PATH I17
J 0
(-5150 3775);
DISPLAY 1.021277 (-5150 3775);
DISPLAY INVISIBLE (-5150 3775);
FORCEADD TAP..1
(300 4500);
FORCEPROP 3 LASTPIN (250 4500) SIG_NAME M_B_CPU1_SA_DQS_DN<8>
J 0
(260 4510);
DISPLAY 0.659574 (260 4510);
PAINT MONO (260 4510);
DISPLAY INVISIBLE (260 4510);
FORCEPROP 1 LASTPIN (250 4500) BN 8
J 0
(238 4508);
DISPLAY 0.680851 (238 4508);
PAINT GREEN (238 4508);
FORCEPROP 2 LAST CDS_LIB standard
J 0
(300 4500);
DISPLAY INVISIBLE (300 4500);
FORCEPROP 1 LAST BODY_TYPE PLUMBING
J 0
(300 4550);
DISPLAY 0.872340 (300 4550);
PAINT GREEN (300 4550);
DISPLAY INVISIBLE (300 4550);
FORCEPROP 1 LAST HDL_TAP TRUE
J 0
(625 4375);
DISPLAY 0.872340 (625 4375);
DISPLAY INVISIBLE (625 4375);
FORCEPROP 1 LAST PATH I170
J 0
(298 4500);
DISPLAY 0.872340 (298 4500);
PAINT GREEN (298 4500);
DISPLAY INVISIBLE (298 4500);
FORCEADD TAP..1
(300 4600);
FORCEPROP 3 LASTPIN (250 4600) SIG_NAME M_B_CPU1_SA_DQS_DN<9>
J 0
(260 4610);
DISPLAY 0.659574 (260 4610);
PAINT MONO (260 4610);
DISPLAY INVISIBLE (260 4610);
FORCEPROP 1 LASTPIN (250 4600) BN 9
J 0
(238 4608);
DISPLAY 0.680851 (238 4608);
PAINT GREEN (238 4608);
FORCEPROP 2 LAST CDS_LIB standard
J 0
(300 4600);
DISPLAY INVISIBLE (300 4600);
FORCEPROP 1 LAST BODY_TYPE PLUMBING
J 0
(300 4650);
DISPLAY 0.872340 (300 4650);
PAINT GREEN (300 4650);
DISPLAY INVISIBLE (300 4650);
FORCEPROP 1 LAST HDL_TAP TRUE
J 0
(625 4475);
DISPLAY 0.872340 (625 4475);
DISPLAY INVISIBLE (625 4475);
FORCEPROP 1 LAST PATH I171
J 0
(298 4600);
DISPLAY 0.872340 (298 4600);
PAINT GREEN (298 4600);
DISPLAY INVISIBLE (298 4600);
FORCEADD TAP..1
(125 4650);
FORCEPROP 3 LASTPIN (75 4650) SIG_NAME M_B_CPU1_SA_DQS_DP<9>
J 0
(85 4660);
DISPLAY 0.659574 (85 4660);
PAINT MONO (85 4660);
DISPLAY INVISIBLE (85 4660);
FORCEPROP 1 LASTPIN (75 4650) BN 9
J 0
(63 4658);
DISPLAY 0.680851 (63 4658);
PAINT GREEN (63 4658);
FORCEPROP 2 LAST CDS_LIB standard
J 0
(125 4650);
DISPLAY INVISIBLE (125 4650);
FORCEPROP 1 LAST BODY_TYPE PLUMBING
J 0
(125 4700);
DISPLAY 0.872340 (125 4700);
PAINT GREEN (125 4700);
DISPLAY INVISIBLE (125 4700);
FORCEPROP 1 LAST HDL_TAP TRUE
J 0
(450 4525);
DISPLAY 0.872340 (450 4525);
DISPLAY INVISIBLE (450 4525);
FORCEPROP 1 LAST PATH I172
J 0
(123 4650);
DISPLAY 0.872340 (123 4650);
PAINT GREEN (123 4650);
DISPLAY INVISIBLE (123 4650);
FORCEADD OFFPAGE..2
(1250 4625);
FORCEPROP 2 LAST $XR1 100 
J 0
(1529 4625);
DISPLAY 0.638298 (1529 4625);
PAINT MONO (1529 4625);
FORCEPROP 2 LAST $XR0 52 
J 0
(1439 4625);
DISPLAY 0.638298 (1439 4625);
PAINT MONO (1439 4625);
FORCEPROP 2 LAST CDS_LIB standard
J 0
(1250 4625);
PAINT MONO (1250 4625);
DISPLAY INVISIBLE (1250 4625);
FORCEPROP 1 LAST OFFPAGE TRUE
J 0
(1575 4500);
DISPLAY 1.170213 (1575 4500);
PAINT GREEN (1575 4500);
DISPLAY INVISIBLE (1575 4500);
FORCEPROP 1 LAST COMMENT_BODY TRUE
J 0
(1205 4530);
DISPLAY 1.170213 (1205 4530);
PAINT GREEN (1205 4530);
DISPLAY INVISIBLE (1205 4530);
FORCEPROP 2 LAST PATH I173
J 0
(1425 4700);
DISPLAY 1.021277 (1425 4700);
DISPLAY INVISIBLE (1425 4700);
FORCEADD OFFPAGE..2
(1250 4675);
FORCEPROP 2 LAST $XR1 100 
J 0
(1529 4675);
DISPLAY 0.638298 (1529 4675);
PAINT MONO (1529 4675);
FORCEPROP 2 LAST $XR0 52 
J 0
(1439 4675);
DISPLAY 0.638298 (1439 4675);
PAINT MONO (1439 4675);
FORCEPROP 2 LAST CDS_LIB standard
J 0
(1250 4675);
PAINT MONO (1250 4675);
DISPLAY INVISIBLE (1250 4675);
FORCEPROP 1 LAST OFFPAGE TRUE
J 0
(1575 4550);
DISPLAY 1.170213 (1575 4550);
PAINT GREEN (1575 4550);
DISPLAY INVISIBLE (1575 4550);
FORCEPROP 1 LAST COMMENT_BODY TRUE
J 0
(1205 4580);
DISPLAY 1.170213 (1205 4580);
PAINT GREEN (1205 4580);
DISPLAY INVISIBLE (1205 4580);
FORCEPROP 2 LAST PATH I174
J 0
(1425 4750);
DISPLAY 1.021277 (1425 4750);
DISPLAY INVISIBLE (1425 4750);
FORCEADD VCC_CORE..1
(1800 5200);
FORCEPROP 3 LASTPIN (1800 5150) SIG_NAME P12V_S3_AUX_CPU1_NVDIMM\g
J 0
(1810 5160);
DISPLAY 0.659574 (1810 5160);
PAINT MONO (1810 5160);
DISPLAY INVISIBLE (1810 5160);
FORCEPROP 1 LAST HDL_POWER P12V_S3_AUX_CPU1_NVDIMM
J 1
(1800 5250);
DISPLAY 1.148936 (1800 5250);
PAINT GREEN (1800 5250);
FORCEPROP 2 LAST CDS_LIB logical_power
J 0
(1800 5200);
PAINT MONO (1800 5200);
DISPLAY INVISIBLE (1800 5200);
FORCEPROP 1 LAST PATH I175
J 0
(1850 5225);
DISPLAY 0.872340 (1850 5225);
PAINT AQUA (1850 5225);
DISPLAY INVISIBLE (1850 5225);
FORCEADD SCONN288_ADR50017P087CC..3
(2650 3025);
FORCEPROP 1 LAST PART_NUMBER DFHST8FS460
J 0
(2195 4949);
DISPLAY 0.723404 (2195 4949);
PAINT GREEN (2195 4949);
DISPLAY INVISIBLE (2195 4949);
FORCEPROP 1 LAST MATERIAL IO
J 0
(2195 4822);
DISPLAY 0.723404 (2195 4822);
PAINT GREEN (2195 4822);
FORCEPROP 2 LAST PART_TYPE SMLF
J 0
(2200 5100);
DISPLAY 1.021277 (2200 5100);
FORCEPROP 2 LAST VALUE SCONN288_ADR50017-P087CC
J 0
(2200 5050);
DISPLAY 1.021277 (2200 5050);
FORCEPROP 1 LAST $LOCATION J20
J 0
(2200 5000);
DISPLAY 0.723404 (2200 5000);
PAINT GREEN (2200 5000);
FORCEPROP 0 LASTPIN (3250 1400) $PN G1
J 0
(3260 1410);
DISPLAY 0.680851 (3260 1410);
PAINT MONO (3260 1410);
FORCEPROP 0 LASTPIN (3250 1350) $PN G2
J 0
(3260 1360);
DISPLAY 0.680851 (3260 1360);
PAINT MONO (3260 1360);
FORCEPROP 0 LASTPIN (3250 1300) $PN G3
J 0
(3260 1310);
DISPLAY 0.680851 (3260 1310);
PAINT MONO (3260 1310);
FORCEPROP 0 LASTPIN (2050 4550) $PN 1
J 2
(2040 4560);
DISPLAY 0.680851 (2040 4560);
PAINT MONO (2040 4560);
FORCEPROP 0 LASTPIN (2050 4600) $PN 145
J 2
(2040 4610);
DISPLAY 0.680851 (2040 4610);
PAINT MONO (2040 4610);
FORCEPROP 0 LASTPIN (2050 4650) $PN 146
J 2
(2040 4660);
DISPLAY 0.680851 (2040 4660);
PAINT MONO (2040 4660);
FORCEPROP 0 LASTPIN (3250 1500) $PN 6
J 0
(3260 1510);
DISPLAY 0.680851 (3260 1510);
PAINT MONO (3260 1510);
FORCEPROP 0 LASTPIN (3250 1550) $PN 8
J 0
(3260 1560);
DISPLAY 0.680851 (3260 1560);
PAINT MONO (3260 1560);
FORCEPROP 0 LASTPIN (3250 1600) $PN 10
J 0
(3260 1610);
DISPLAY 0.680851 (3260 1610);
PAINT MONO (3260 1610);
FORCEPROP 0 LASTPIN (3250 1650) $PN 13
J 0
(3260 1660);
DISPLAY 0.680851 (3260 1660);
PAINT MONO (3260 1660);
FORCEPROP 0 LASTPIN (3250 1700) $PN 15
J 0
(3260 1710);
DISPLAY 0.680851 (3260 1710);
PAINT MONO (3260 1710);
FORCEPROP 0 LASTPIN (3250 1750) $PN 17
J 0
(3260 1760);
DISPLAY 0.680851 (3260 1760);
PAINT MONO (3260 1760);
FORCEPROP 0 LASTPIN (3250 1800) $PN 19
J 0
(3260 1810);
DISPLAY 0.680851 (3260 1810);
PAINT MONO (3260 1810);
FORCEPROP 0 LASTPIN (3250 1850) $PN 21
J 0
(3260 1860);
DISPLAY 0.680851 (3260 1860);
PAINT MONO (3260 1860);
FORCEPROP 0 LASTPIN (3250 1900) $PN 24
J 0
(3260 1910);
DISPLAY 0.680851 (3260 1910);
PAINT MONO (3260 1910);
FORCEPROP 0 LASTPIN (3250 1950) $PN 26
J 0
(3260 1960);
DISPLAY 0.680851 (3260 1960);
PAINT MONO (3260 1960);
FORCEPROP 0 LASTPIN (3250 2000) $PN 28
J 0
(3260 2010);
DISPLAY 0.680851 (3260 2010);
PAINT MONO (3260 2010);
FORCEPROP 0 LASTPIN (3250 2050) $PN 30
J 0
(3260 2060);
DISPLAY 0.680851 (3260 2060);
PAINT MONO (3260 2060);
FORCEPROP 0 LASTPIN (3250 2100) $PN 32
J 0
(3260 2110);
DISPLAY 0.680851 (3260 2110);
PAINT MONO (3260 2110);
FORCEPROP 0 LASTPIN (3250 2150) $PN 35
J 0
(3260 2160);
DISPLAY 0.680851 (3260 2160);
PAINT MONO (3260 2160);
FORCEPROP 0 LASTPIN (3250 2200) $PN 37
J 0
(3260 2210);
DISPLAY 0.680851 (3260 2210);
PAINT MONO (3260 2210);
FORCEPROP 0 LASTPIN (3250 2250) $PN 39
J 0
(3260 2260);
DISPLAY 0.680851 (3260 2260);
PAINT MONO (3260 2260);
FORCEPROP 0 LASTPIN (3250 2300) $PN 41
J 0
(3260 2310);
DISPLAY 0.680851 (3260 2310);
PAINT MONO (3260 2310);
FORCEPROP 0 LASTPIN (3250 2350) $PN 43
J 0
(3260 2360);
DISPLAY 0.680851 (3260 2360);
PAINT MONO (3260 2360);
FORCEPROP 0 LASTPIN (3250 2400) $PN 46
J 0
(3260 2410);
DISPLAY 0.680851 (3260 2410);
PAINT MONO (3260 2410);
FORCEPROP 0 LASTPIN (3250 2450) $PN 48
J 0
(3260 2460);
DISPLAY 0.680851 (3260 2460);
PAINT MONO (3260 2460);
FORCEPROP 0 LASTPIN (3250 2500) $PN 50
J 0
(3260 2510);
DISPLAY 0.680851 (3260 2510);
PAINT MONO (3260 2510);
FORCEPROP 0 LASTPIN (3250 2550) $PN 52
J 0
(3260 2560);
DISPLAY 0.680851 (3260 2560);
PAINT MONO (3260 2560);
FORCEPROP 0 LASTPIN (3250 2600) $PN 54
J 0
(3260 2610);
DISPLAY 0.680851 (3260 2610);
PAINT MONO (3260 2610);
FORCEPROP 0 LASTPIN (3250 2650) $PN 57
J 0
(3260 2660);
DISPLAY 0.680851 (3260 2660);
PAINT MONO (3260 2660);
FORCEPROP 0 LASTPIN (3250 2700) $PN 59
J 0
(3260 2710);
DISPLAY 0.680851 (3260 2710);
PAINT MONO (3260 2710);
FORCEPROP 0 LASTPIN (3250 2750) $PN 61
J 0
(3260 2760);
DISPLAY 0.680851 (3260 2760);
PAINT MONO (3260 2760);
FORCEPROP 0 LASTPIN (3250 2800) $PN 63
J 0
(3260 2810);
DISPLAY 0.680851 (3260 2810);
PAINT MONO (3260 2810);
FORCEPROP 0 LASTPIN (3250 2850) $PN 65
J 0
(3260 2860);
DISPLAY 0.680851 (3260 2860);
PAINT MONO (3260 2860);
FORCEPROP 0 LASTPIN (3250 2900) $PN 67
J 0
(3260 2910);
DISPLAY 0.680851 (3260 2910);
PAINT MONO (3260 2910);
FORCEPROP 0 LASTPIN (3250 2950) $PN 69
J 0
(3260 2960);
DISPLAY 0.680851 (3260 2960);
PAINT MONO (3260 2960);
FORCEPROP 0 LASTPIN (3250 3000) $PN 71
J 0
(3260 3010);
DISPLAY 0.680851 (3260 3010);
PAINT MONO (3260 3010);
FORCEPROP 0 LASTPIN (3250 3050) $PN 73
J 0
(3260 3060);
DISPLAY 0.680851 (3260 3060);
PAINT MONO (3260 3060);
FORCEPROP 0 LASTPIN (3250 3100) $PN 75
J 0
(3260 3110);
DISPLAY 0.680851 (3260 3110);
PAINT MONO (3260 3110);
FORCEPROP 0 LASTPIN (3250 3150) $PN 77
J 0
(3260 3160);
DISPLAY 0.680851 (3260 3160);
PAINT MONO (3260 3160);
FORCEPROP 0 LASTPIN (3250 3200) $PN 79
J 0
(3260 3210);
DISPLAY 0.680851 (3260 3210);
PAINT MONO (3260 3210);
FORCEPROP 0 LASTPIN (3250 3250) $PN 81
J 0
(3260 3260);
DISPLAY 0.680851 (3260 3260);
PAINT MONO (3260 3260);
FORCEPROP 0 LASTPIN (3250 3300) $PN 83
J 0
(3260 3310);
DISPLAY 0.680851 (3260 3310);
PAINT MONO (3260 3310);
FORCEPROP 0 LASTPIN (3250 3350) $PN 85
J 0
(3260 3360);
DISPLAY 0.680851 (3260 3360);
PAINT MONO (3260 3360);
FORCEPROP 0 LASTPIN (3250 3400) $PN 88
J 0
(3260 3410);
DISPLAY 0.680851 (3260 3410);
PAINT MONO (3260 3410);
FORCEPROP 0 LASTPIN (3250 3450) $PN 90
J 0
(3260 3460);
DISPLAY 0.680851 (3260 3460);
PAINT MONO (3260 3460);
FORCEPROP 0 LASTPIN (3250 3500) $PN 92
J 0
(3260 3510);
DISPLAY 0.680851 (3260 3510);
PAINT MONO (3260 3510);
FORCEPROP 0 LASTPIN (3250 3550) $PN 95
J 0
(3260 3560);
DISPLAY 0.680851 (3260 3560);
PAINT MONO (3260 3560);
FORCEPROP 0 LASTPIN (3250 3600) $PN 97
J 0
(3260 3610);
DISPLAY 0.680851 (3260 3610);
PAINT MONO (3260 3610);
FORCEPROP 0 LASTPIN (3250 3650) $PN 99
J 0
(3260 3660);
DISPLAY 0.680851 (3260 3660);
PAINT MONO (3260 3660);
FORCEPROP 0 LASTPIN (3250 3700) $PN 101
J 0
(3260 3710);
DISPLAY 0.680851 (3260 3710);
PAINT MONO (3260 3710);
FORCEPROP 0 LASTPIN (3250 3750) $PN 103
J 0
(3260 3760);
DISPLAY 0.680851 (3260 3760);
PAINT MONO (3260 3760);
FORCEPROP 0 LASTPIN (3250 3800) $PN 106
J 0
(3260 3810);
DISPLAY 0.680851 (3260 3810);
PAINT MONO (3260 3810);
FORCEPROP 0 LASTPIN (3250 3850) $PN 108
J 0
(3260 3860);
DISPLAY 0.680851 (3260 3860);
PAINT MONO (3260 3860);
FORCEPROP 0 LASTPIN (3250 3900) $PN 110
J 0
(3260 3910);
DISPLAY 0.680851 (3260 3910);
PAINT MONO (3260 3910);
FORCEPROP 0 LASTPIN (3250 3950) $PN 112
J 0
(3260 3960);
DISPLAY 0.680851 (3260 3960);
PAINT MONO (3260 3960);
FORCEPROP 0 LASTPIN (3250 4000) $PN 114
J 0
(3260 4010);
DISPLAY 0.680851 (3260 4010);
PAINT MONO (3260 4010);
FORCEPROP 0 LASTPIN (3250 4050) $PN 117
J 0
(3260 4060);
DISPLAY 0.680851 (3260 4060);
PAINT MONO (3260 4060);
FORCEPROP 0 LASTPIN (3250 4100) $PN 119
J 0
(3260 4110);
DISPLAY 0.680851 (3260 4110);
PAINT MONO (3260 4110);
FORCEPROP 0 LASTPIN (3250 4150) $PN 121
J 0
(3260 4160);
DISPLAY 0.680851 (3260 4160);
PAINT MONO (3260 4160);
FORCEPROP 0 LASTPIN (3250 4200) $PN 123
J 0
(3260 4210);
DISPLAY 0.680851 (3260 4210);
PAINT MONO (3260 4210);
FORCEPROP 0 LASTPIN (3250 4250) $PN 125
J 0
(3260 4260);
DISPLAY 0.680851 (3260 4260);
PAINT MONO (3260 4260);
FORCEPROP 0 LASTPIN (3250 4300) $PN 128
J 0
(3260 4310);
DISPLAY 0.680851 (3260 4310);
PAINT MONO (3260 4310);
FORCEPROP 0 LASTPIN (3250 4350) $PN 130
J 0
(3260 4360);
DISPLAY 0.680851 (3260 4360);
PAINT MONO (3260 4360);
FORCEPROP 0 LASTPIN (3250 4400) $PN 132
J 0
(3260 4410);
DISPLAY 0.680851 (3260 4410);
PAINT MONO (3260 4410);
FORCEPROP 0 LASTPIN (3250 4450) $PN 134
J 0
(3260 4460);
DISPLAY 0.680851 (3260 4460);
PAINT MONO (3260 4460);
FORCEPROP 0 LASTPIN (3250 4500) $PN 136
J 0
(3260 4510);
DISPLAY 0.680851 (3260 4510);
PAINT MONO (3260 4510);
FORCEPROP 0 LASTPIN (3250 4550) $PN 139
J 0
(3260 4560);
DISPLAY 0.680851 (3260 4560);
PAINT MONO (3260 4560);
FORCEPROP 0 LASTPIN (3250 4600) $PN 141
J 0
(3260 4610);
DISPLAY 0.680851 (3260 4610);
PAINT MONO (3260 4610);
FORCEPROP 0 LASTPIN (3250 4650) $PN 143
J 0
(3260 4660);
DISPLAY 0.680851 (3260 4660);
PAINT MONO (3260 4660);
FORCEPROP 0 LASTPIN (2050 1400) $PN 151
J 2
(2040 1410);
DISPLAY 0.680851 (2040 1410);
PAINT MONO (2040 1410);
FORCEPROP 0 LASTPIN (2050 1450) $PN 153
J 2
(2040 1460);
DISPLAY 0.680851 (2040 1460);
PAINT MONO (2040 1460);
FORCEPROP 0 LASTPIN (2050 1500) $PN 155
J 2
(2040 1510);
DISPLAY 0.680851 (2040 1510);
PAINT MONO (2040 1510);
FORCEPROP 0 LASTPIN (2050 1550) $PN 158
J 2
(2040 1560);
DISPLAY 0.680851 (2040 1560);
PAINT MONO (2040 1560);
FORCEPROP 0 LASTPIN (2050 1600) $PN 160
J 2
(2040 1610);
DISPLAY 0.680851 (2040 1610);
PAINT MONO (2040 1610);
FORCEPROP 0 LASTPIN (2050 1650) $PN 162
J 2
(2040 1660);
DISPLAY 0.680851 (2040 1660);
PAINT MONO (2040 1660);
FORCEPROP 0 LASTPIN (2050 1700) $PN 164
J 2
(2040 1710);
DISPLAY 0.680851 (2040 1710);
PAINT MONO (2040 1710);
FORCEPROP 0 LASTPIN (2050 1750) $PN 166
J 2
(2040 1760);
DISPLAY 0.680851 (2040 1760);
PAINT MONO (2040 1760);
FORCEPROP 0 LASTPIN (2050 1800) $PN 169
J 2
(2040 1810);
DISPLAY 0.680851 (2040 1810);
PAINT MONO (2040 1810);
FORCEPROP 0 LASTPIN (2050 1850) $PN 171
J 2
(2040 1860);
DISPLAY 0.680851 (2040 1860);
PAINT MONO (2040 1860);
FORCEPROP 0 LASTPIN (2050 1900) $PN 173
J 2
(2040 1910);
DISPLAY 0.680851 (2040 1910);
PAINT MONO (2040 1910);
FORCEPROP 0 LASTPIN (2050 1950) $PN 175
J 2
(2040 1960);
DISPLAY 0.680851 (2040 1960);
PAINT MONO (2040 1960);
FORCEPROP 0 LASTPIN (2050 2000) $PN 177
J 2
(2040 2010);
DISPLAY 0.680851 (2040 2010);
PAINT MONO (2040 2010);
FORCEPROP 0 LASTPIN (2050 2050) $PN 180
J 2
(2040 2060);
DISPLAY 0.680851 (2040 2060);
PAINT MONO (2040 2060);
FORCEPROP 0 LASTPIN (2050 2100) $PN 182
J 2
(2040 2110);
DISPLAY 0.680851 (2040 2110);
PAINT MONO (2040 2110);
FORCEPROP 0 LASTPIN (2050 2150) $PN 184
J 2
(2040 2160);
DISPLAY 0.680851 (2040 2160);
PAINT MONO (2040 2160);
FORCEPROP 0 LASTPIN (2050 2200) $PN 186
J 2
(2040 2210);
DISPLAY 0.680851 (2040 2210);
PAINT MONO (2040 2210);
FORCEPROP 0 LASTPIN (2050 2250) $PN 188
J 2
(2040 2260);
DISPLAY 0.680851 (2040 2260);
PAINT MONO (2040 2260);
FORCEPROP 0 LASTPIN (2050 2300) $PN 191
J 2
(2040 2310);
DISPLAY 0.680851 (2040 2310);
PAINT MONO (2040 2310);
FORCEPROP 0 LASTPIN (2050 2350) $PN 193
J 2
(2040 2360);
DISPLAY 0.680851 (2040 2360);
PAINT MONO (2040 2360);
FORCEPROP 0 LASTPIN (2050 2400) $PN 195
J 2
(2040 2410);
DISPLAY 0.680851 (2040 2410);
PAINT MONO (2040 2410);
FORCEPROP 0 LASTPIN (2050 2450) $PN 197
J 2
(2040 2460);
DISPLAY 0.680851 (2040 2460);
PAINT MONO (2040 2460);
FORCEPROP 0 LASTPIN (2050 2500) $PN 199
J 2
(2040 2510);
DISPLAY 0.680851 (2040 2510);
PAINT MONO (2040 2510);
FORCEPROP 0 LASTPIN (2050 2550) $PN 202
J 2
(2040 2560);
DISPLAY 0.680851 (2040 2560);
PAINT MONO (2040 2560);
FORCEPROP 0 LASTPIN (2050 2600) $PN 204
J 2
(2040 2610);
DISPLAY 0.680851 (2040 2610);
PAINT MONO (2040 2610);
FORCEPROP 0 LASTPIN (2050 2650) $PN 206
J 2
(2040 2660);
DISPLAY 0.680851 (2040 2660);
PAINT MONO (2040 2660);
FORCEPROP 0 LASTPIN (2050 2700) $PN 208
J 2
(2040 2710);
DISPLAY 0.680851 (2040 2710);
PAINT MONO (2040 2710);
FORCEPROP 0 LASTPIN (2050 2750) $PN 210
J 2
(2040 2760);
DISPLAY 0.680851 (2040 2760);
PAINT MONO (2040 2760);
FORCEPROP 0 LASTPIN (2050 2800) $PN 212
J 2
(2040 2810);
DISPLAY 0.680851 (2040 2810);
PAINT MONO (2040 2810);
FORCEPROP 0 LASTPIN (2050 2850) $PN 214
J 2
(2040 2860);
DISPLAY 0.680851 (2040 2860);
PAINT MONO (2040 2860);
FORCEPROP 0 LASTPIN (2050 2900) $PN 216
J 2
(2040 2910);
DISPLAY 0.680851 (2040 2910);
PAINT MONO (2040 2910);
FORCEPROP 0 LASTPIN (2050 2950) $PN 219
J 2
(2040 2960);
DISPLAY 0.680851 (2040 2960);
PAINT MONO (2040 2960);
FORCEPROP 0 LASTPIN (2050 3000) $PN 222
J 2
(2040 3010);
DISPLAY 0.680851 (2040 3010);
PAINT MONO (2040 3010);
FORCEPROP 0 LASTPIN (2050 3050) $PN 224
J 2
(2040 3060);
DISPLAY 0.680851 (2040 3060);
PAINT MONO (2040 3060);
FORCEPROP 0 LASTPIN (2050 3100) $PN 226
J 2
(2040 3110);
DISPLAY 0.680851 (2040 3110);
PAINT MONO (2040 3110);
FORCEPROP 0 LASTPIN (2050 3150) $PN 228
J 2
(2040 3160);
DISPLAY 0.680851 (2040 3160);
PAINT MONO (2040 3160);
FORCEPROP 0 LASTPIN (2050 3200) $PN 230
J 2
(2040 3210);
DISPLAY 0.680851 (2040 3210);
PAINT MONO (2040 3210);
FORCEPROP 0 LASTPIN (2050 3250) $PN 233
J 2
(2040 3260);
DISPLAY 0.680851 (2040 3260);
PAINT MONO (2040 3260);
FORCEPROP 0 LASTPIN (2050 3300) $PN 235
J 2
(2040 3310);
DISPLAY 0.680851 (2040 3310);
PAINT MONO (2040 3310);
FORCEPROP 0 LASTPIN (2050 3350) $PN 237
J 2
(2040 3360);
DISPLAY 0.680851 (2040 3360);
PAINT MONO (2040 3360);
FORCEPROP 0 LASTPIN (2050 3400) $PN 240
J 2
(2040 3410);
DISPLAY 0.680851 (2040 3410);
PAINT MONO (2040 3410);
FORCEPROP 0 LASTPIN (2050 3450) $PN 242
J 2
(2040 3460);
DISPLAY 0.680851 (2040 3460);
PAINT MONO (2040 3460);
FORCEPROP 0 LASTPIN (2050 3500) $PN 244
J 2
(2040 3510);
DISPLAY 0.680851 (2040 3510);
PAINT MONO (2040 3510);
FORCEPROP 0 LASTPIN (2050 3550) $PN 246
J 2
(2040 3560);
DISPLAY 0.680851 (2040 3560);
PAINT MONO (2040 3560);
FORCEPROP 0 LASTPIN (2050 3600) $PN 248
J 2
(2040 3610);
DISPLAY 0.680851 (2040 3610);
PAINT MONO (2040 3610);
FORCEPROP 0 LASTPIN (2050 3650) $PN 251
J 2
(2040 3660);
DISPLAY 0.680851 (2040 3660);
PAINT MONO (2040 3660);
FORCEPROP 0 LASTPIN (2050 3700) $PN 253
J 2
(2040 3710);
DISPLAY 0.680851 (2040 3710);
PAINT MONO (2040 3710);
FORCEPROP 0 LASTPIN (2050 3750) $PN 255
J 2
(2040 3760);
DISPLAY 0.680851 (2040 3760);
PAINT MONO (2040 3760);
FORCEPROP 0 LASTPIN (2050 3800) $PN 257
J 2
(2040 3810);
DISPLAY 0.680851 (2040 3810);
PAINT MONO (2040 3810);
FORCEPROP 0 LASTPIN (2050 3850) $PN 259
J 2
(2040 3860);
DISPLAY 0.680851 (2040 3860);
PAINT MONO (2040 3860);
FORCEPROP 0 LASTPIN (2050 3900) $PN 262
J 2
(2040 3910);
DISPLAY 0.680851 (2040 3910);
PAINT MONO (2040 3910);
FORCEPROP 0 LASTPIN (2050 3950) $PN 264
J 2
(2040 3960);
DISPLAY 0.680851 (2040 3960);
PAINT MONO (2040 3960);
FORCEPROP 0 LASTPIN (2050 4000) $PN 266
J 2
(2040 4010);
DISPLAY 0.680851 (2040 4010);
PAINT MONO (2040 4010);
FORCEPROP 0 LASTPIN (2050 4050) $PN 268
J 2
(2040 4060);
DISPLAY 0.680851 (2040 4060);
PAINT MONO (2040 4060);
FORCEPROP 0 LASTPIN (2050 4100) $PN 270
J 2
(2040 4110);
DISPLAY 0.680851 (2040 4110);
PAINT MONO (2040 4110);
FORCEPROP 0 LASTPIN (2050 4150) $PN 273
J 2
(2040 4160);
DISPLAY 0.680851 (2040 4160);
PAINT MONO (2040 4160);
FORCEPROP 0 LASTPIN (2050 4200) $PN 275
J 2
(2040 4210);
DISPLAY 0.680851 (2040 4210);
PAINT MONO (2040 4210);
FORCEPROP 0 LASTPIN (2050 4250) $PN 277
J 2
(2040 4260);
DISPLAY 0.680851 (2040 4260);
PAINT MONO (2040 4260);
FORCEPROP 0 LASTPIN (2050 4300) $PN 279
J 2
(2040 4310);
DISPLAY 0.680851 (2040 4310);
PAINT MONO (2040 4310);
FORCEPROP 0 LASTPIN (2050 4350) $PN 281
J 2
(2040 4360);
DISPLAY 0.680851 (2040 4360);
PAINT MONO (2040 4360);
FORCEPROP 0 LASTPIN (2050 4400) $PN 284
J 2
(2040 4410);
DISPLAY 0.680851 (2040 4410);
PAINT MONO (2040 4410);
FORCEPROP 0 LASTPIN (2050 4450) $PN 286
J 2
(2040 4460);
DISPLAY 0.680851 (2040 4460);
PAINT MONO (2040 4460);
FORCEPROP 0 LASTPIN (2050 4500) $PN 288
J 2
(2040 4510);
DISPLAY 0.680851 (2040 4510);
PAINT MONO (2040 4510);
FORCEPROP 1 LAST NEEDS_NO_SIZE TRUE
J 0
(2650 3025);
DISPLAY 0.723404 (2650 3025);
PAINT GREEN (2650 3025);
DISPLAY INVISIBLE (2650 3025);
FORCEPROP 1 LAST CDS_LMAN_SYM_OUTLINE -450,1775,450,-1775
J 0
(2650 3025);
DISPLAY 0.468085 (2650 3025);
PAINT GREEN (2650 3025);
DISPLAY INVISIBLE (2650 3025);
FORCEPROP 2 LAST CDS_LIB pure_quanta
J 0
(2650 3025);
DISPLAY INVISIBLE (2650 3025);
FORCEPROP 1 LAST PATH I176
J 0
(2650 3025);
DISPLAY 0.723404 (2650 3025);
PAINT GREEN (2650 3025);
DISPLAY INVISIBLE (2650 3025);
FORCEPROP 2 LAST CDS_LOCATION J20
J 0
(2200 5150);
DISPLAY 1.021277 (2200 5150);
DISPLAY INVISIBLE (2200 5150);
FORCEPROP 0 LAST $SEC 3
J 0
(2200 5150);
DISPLAY 0.680851 (2200 5150);
PAINT MONO (2200 5150);
DISPLAY INVISIBLE (2200 5150);
FORCEPROP 2 LAST CDS_SEC 3
J 0
(2200 5150);
DISPLAY 1.021277 (2200 5150);
DISPLAY INVISIBLE (2200 5150);
FORCEADD UNIVERSAL_GND..1
(3500 950);
FORCEPROP 3 LASTPIN (3500 1000) SIG_NAME GND\g
J 0
(3510 1010);
DISPLAY 0.659574 (3510 1010);
PAINT MONO (3510 1010);
DISPLAY INVISIBLE (3510 1010);
FORCEPROP 1 LAST PATH I177
J 0
(3575 950);
DISPLAY 0.872340 (3575 950);
PAINT AQUA (3575 950);
DISPLAY INVISIBLE (3575 950);
FORCEPROP 1 LAST HDL_POWER GND
J 1
(3525 875);
DISPLAY 0.872340 (3525 875);
PAINT GREEN (3525 875);
DISPLAY INVISIBLE (3525 875);
FORCEPROP 2 LAST CDS_LIB logical_power
J 0
(3500 950);
PAINT MONO (3500 950);
DISPLAY INVISIBLE (3500 950);
FORCEADD SCONN288_ADR50017P087CC..2
(-775 3650);
FORCEPROP 1 LAST PART_NUMBER DFHST8FS460
J 0
(-1380 4938);
DISPLAY 0.723404 (-1380 4938);
PAINT GREEN (-1380 4938);
DISPLAY INVISIBLE (-1380 4938);
FORCEPROP 2 LAST PART_TYPE SMLF
J 0
(-1375 5175);
DISPLAY 1.021277 (-1375 5175);
FORCEPROP 1 LAST MATERIAL IO
J 0
(-1380 4811);
DISPLAY 0.723404 (-1380 4811);
PAINT GREEN (-1380 4811);
FORCEPROP 2 LAST VALUE SCONN288_ADR50017-P087CC
J 0
(-1375 5125);
DISPLAY 1.021277 (-1375 5125);
FORCEPROP 1 LAST LOCATION J20
J 0
(-1380 5085);
DISPLAY 0.723404 (-1380 5085);
PAINT GREEN (-1380 5085);
FORCEPROP 0 LASTPIN (-25 3700) $PN 12
J 0
(-15 3710);
DISPLAY 0.680851 (-15 3710);
PAINT MONO (-15 3710);
FORCEPROP 0 LASTPIN (-25 3750) $PN 11
J 0
(-15 3760);
DISPLAY 0.680851 (-15 3760);
PAINT MONO (-15 3760);
FORCEPROP 0 LASTPIN (-25 2650) $PN 105
J 0
(-15 2660);
DISPLAY 0.680851 (-15 2660);
PAINT MONO (-15 2660);
FORCEPROP 0 LASTPIN (-25 2700) $PN 104
J 0
(-15 2710);
DISPLAY 0.680851 (-15 2710);
PAINT MONO (-15 2710);
FORCEPROP 0 LASTPIN (-25 3800) $PN 23
J 0
(-15 3810);
DISPLAY 0.680851 (-15 3810);
PAINT MONO (-15 3810);
FORCEPROP 0 LASTPIN (-25 3850) $PN 22
J 0
(-15 3860);
DISPLAY 0.680851 (-15 3860);
PAINT MONO (-15 3860);
FORCEPROP 0 LASTPIN (-25 2750) $PN 116
J 0
(-15 2760);
DISPLAY 0.680851 (-15 2760);
PAINT MONO (-15 2760);
FORCEPROP 0 LASTPIN (-25 2800) $PN 115
J 0
(-15 2810);
DISPLAY 0.680851 (-15 2810);
PAINT MONO (-15 2810);
FORCEPROP 0 LASTPIN (-25 3900) $PN 34
J 0
(-15 3910);
DISPLAY 0.680851 (-15 3910);
PAINT MONO (-15 3910);
FORCEPROP 0 LASTPIN (-25 3950) $PN 33
J 0
(-15 3960);
DISPLAY 0.680851 (-15 3960);
PAINT MONO (-15 3960);
FORCEPROP 0 LASTPIN (-25 2850) $PN 127
J 0
(-15 2860);
DISPLAY 0.680851 (-15 2860);
PAINT MONO (-15 2860);
FORCEPROP 0 LASTPIN (-25 2900) $PN 126
J 0
(-15 2910);
DISPLAY 0.680851 (-15 2910);
PAINT MONO (-15 2910);
FORCEPROP 0 LASTPIN (-25 4000) $PN 45
J 0
(-15 4010);
DISPLAY 0.680851 (-15 4010);
PAINT MONO (-15 4010);
FORCEPROP 0 LASTPIN (-25 4050) $PN 44
J 0
(-15 4060);
DISPLAY 0.680851 (-15 4060);
PAINT MONO (-15 4060);
FORCEPROP 0 LASTPIN (-25 2950) $PN 138
J 0
(-15 2960);
DISPLAY 0.680851 (-15 2960);
PAINT MONO (-15 2960);
FORCEPROP 0 LASTPIN (-25 3000) $PN 137
J 0
(-15 3010);
DISPLAY 0.680851 (-15 3010);
PAINT MONO (-15 3010);
FORCEPROP 0 LASTPIN (-25 4100) $PN 56
J 0
(-15 4110);
DISPLAY 0.680851 (-15 4110);
PAINT MONO (-15 4110);
FORCEPROP 0 LASTPIN (-25 4150) $PN 55
J 0
(-15 4160);
DISPLAY 0.680851 (-15 4160);
PAINT MONO (-15 4160);
FORCEPROP 0 LASTPIN (-25 3050) $PN 238
J 0
(-15 3060);
DISPLAY 0.680851 (-15 3060);
PAINT MONO (-15 3060);
FORCEPROP 0 LASTPIN (-25 3100) $PN 239
J 0
(-15 3110);
DISPLAY 0.680851 (-15 3110);
PAINT MONO (-15 3110);
FORCEPROP 0 LASTPIN (-25 4200) $PN 156
J 0
(-15 4210);
DISPLAY 0.680851 (-15 4210);
PAINT MONO (-15 4210);
FORCEPROP 0 LASTPIN (-25 4250) $PN 157
J 0
(-15 4260);
DISPLAY 0.680851 (-15 4260);
PAINT MONO (-15 4260);
FORCEPROP 0 LASTPIN (-25 3150) $PN 249
J 0
(-15 3160);
DISPLAY 0.680851 (-15 3160);
PAINT MONO (-15 3160);
FORCEPROP 0 LASTPIN (-25 3200) $PN 250
J 0
(-15 3210);
DISPLAY 0.680851 (-15 3210);
PAINT MONO (-15 3210);
FORCEPROP 0 LASTPIN (-25 4300) $PN 167
J 0
(-15 4310);
DISPLAY 0.680851 (-15 4310);
PAINT MONO (-15 4310);
FORCEPROP 0 LASTPIN (-25 4350) $PN 168
J 0
(-15 4360);
DISPLAY 0.680851 (-15 4360);
PAINT MONO (-15 4360);
FORCEPROP 0 LASTPIN (-25 3250) $PN 260
J 0
(-15 3260);
DISPLAY 0.680851 (-15 3260);
PAINT MONO (-15 3260);
FORCEPROP 0 LASTPIN (-25 3300) $PN 261
J 0
(-15 3310);
DISPLAY 0.680851 (-15 3310);
PAINT MONO (-15 3310);
FORCEPROP 0 LASTPIN (-25 4400) $PN 178
J 0
(-15 4410);
DISPLAY 0.680851 (-15 4410);
PAINT MONO (-15 4410);
FORCEPROP 0 LASTPIN (-25 4450) $PN 179
J 0
(-15 4460);
DISPLAY 0.680851 (-15 4460);
PAINT MONO (-15 4460);
FORCEPROP 0 LASTPIN (-25 3350) $PN 271
J 0
(-15 3360);
DISPLAY 0.680851 (-15 3360);
PAINT MONO (-15 3360);
FORCEPROP 0 LASTPIN (-25 3400) $PN 272
J 0
(-15 3410);
DISPLAY 0.680851 (-15 3410);
PAINT MONO (-15 3410);
FORCEPROP 0 LASTPIN (-25 4500) $PN 189
J 0
(-15 4510);
DISPLAY 0.680851 (-15 4510);
PAINT MONO (-15 4510);
FORCEPROP 0 LASTPIN (-25 4550) $PN 190
J 0
(-15 4560);
DISPLAY 0.680851 (-15 4560);
PAINT MONO (-15 4560);
FORCEPROP 0 LASTPIN (-25 3450) $PN 282
J 0
(-15 3460);
DISPLAY 0.680851 (-15 3460);
PAINT MONO (-15 3460);
FORCEPROP 0 LASTPIN (-25 3500) $PN 283
J 0
(-15 3510);
DISPLAY 0.680851 (-15 3510);
PAINT MONO (-15 3510);
FORCEPROP 0 LASTPIN (-25 4600) $PN 200
J 0
(-15 4610);
DISPLAY 0.680851 (-15 4610);
PAINT MONO (-15 4610);
FORCEPROP 0 LASTPIN (-25 4650) $PN 201
J 0
(-15 4660);
DISPLAY 0.680851 (-15 4660);
PAINT MONO (-15 4660);
FORCEPROP 0 LASTPIN (-25 3550) $PN 94
J 0
(-15 3560);
DISPLAY 0.680851 (-15 3560);
PAINT MONO (-15 3560);
FORCEPROP 0 LASTPIN (-25 3600) $PN 93
J 0
(-15 3610);
DISPLAY 0.680851 (-15 3610);
PAINT MONO (-15 3610);
FORCEPROP 1 LAST NEEDS_NO_SIZE TRUE
J 0
(-775 3650);
DISPLAY 0.723404 (-775 3650);
PAINT GREEN (-775 3650);
DISPLAY INVISIBLE (-775 3650);
FORCEPROP 1 LAST CDS_LMAN_SYM_OUTLINE -600,1150,600,-1150
J 0
(-775 3650);
DISPLAY 0.468085 (-775 3650);
PAINT GREEN (-775 3650);
DISPLAY INVISIBLE (-775 3650);
FORCEPROP 2 LAST CDS_LIB pure_quanta
J 0
(-775 3650);
DISPLAY INVISIBLE (-775 3650);
FORCEPROP 1 LAST PATH I178
J 0
(-775 3650);
DISPLAY 0.723404 (-775 3650);
PAINT GREEN (-775 3650);
DISPLAY INVISIBLE (-775 3650);
FORCEPROP 0 LAST $SEC 2
J 0
(-1375 5225);
DISPLAY 0.680851 (-1375 5225);
PAINT MONO (-1375 5225);
DISPLAY INVISIBLE (-1375 5225);
FORCEPROP 0 LAST CDS_SEC 2
J 0
(-1375 5225);
DISPLAY 1.021277 (-1375 5225);
DISPLAY INVISIBLE (-1375 5225);
FORCEADD OFFPAGE..1
(-4025 1875);
FORCEPROP 2 LAST $XR7 105 
J 0
(-5057 1875);
DISPLAY 0.638298 (-5057 1875);
PAINT MONO (-5057 1875);
FORCEPROP 2 LAST $XR6 104 
J 0
(-4937 1875);
DISPLAY 0.638298 (-4937 1875);
PAINT MONO (-4937 1875);
FORCEPROP 2 LAST $XR5 103 
J 0
(-4817 1875);
DISPLAY 0.638298 (-4817 1875);
PAINT MONO (-4817 1875);
FORCEPROP 2 LAST $XR4 102 
J 0
(-4697 1875);
DISPLAY 0.638298 (-4697 1875);
PAINT MONO (-4697 1875);
FORCEPROP 2 LAST $XR3 100 
J 0
(-4577 1875);
DISPLAY 0.638298 (-4577 1875);
PAINT MONO (-4577 1875);
FORCEPROP 2 LAST $XR2 99 
J 0
(-4457 1875);
DISPLAY 0.638298 (-4457 1875);
PAINT MONO (-4457 1875);
FORCEPROP 2 LAST $XR1 98 
J 0
(-4367 1875);
DISPLAY 0.638298 (-4367 1875);
PAINT MONO (-4367 1875);
FORCEPROP 2 LAST $XR0 230 
J 0
(-4277 1875);
DISPLAY 0.638298 (-4277 1875);
PAINT MONO (-4277 1875);
FORCEPROP 2 LAST CDS_LIB standard
J 2
(-4025 1875);
DISPLAY INVISIBLE (-4025 1875);
FORCEPROP 1 LAST OFFPAGE TRUE
J 0
(-3700 1750);
DISPLAY 0.872340 (-3700 1750);
DISPLAY INVISIBLE (-3700 1750);
FORCEPROP 1 LAST COMMENT_BODY TRUE
J 0
(-3900 1775);
DISPLAY 0.872340 (-3900 1775);
PAINT GREEN (-3900 1775);
DISPLAY INVISIBLE (-3900 1775);
FORCEPROP 2 LAST PATH I179
J 2
(-4200 1950);
DISPLAY 1.021277 (-4200 1950);
DISPLAY INVISIBLE (-4200 1950);
FORCEADD OFFPAGE..1
(-5200 3650);
FORCEPROP 2 LAST $XR0 52 
J 0
(-5421 3650);
DISPLAY 0.638298 (-5421 3650);
PAINT MONO (-5421 3650);
FORCEPROP 2 LAST CDS_LIB standard
J 0
(-5200 3650);
PAINT MONO (-5200 3650);
DISPLAY INVISIBLE (-5200 3650);
FORCEPROP 1 LAST OFFPAGE TRUE
J 0
(-4875 3525);
DISPLAY 0.872340 (-4875 3525);
DISPLAY INVISIBLE (-4875 3525);
FORCEPROP 1 LAST COMMENT_BODY TRUE
J 0
(-5075 3550);
DISPLAY 0.872340 (-5075 3550);
PAINT GREEN (-5075 3550);
DISPLAY INVISIBLE (-5075 3550);
FORCEPROP 2 LAST PATH I18
J 0
(-5150 3725);
DISPLAY 1.021277 (-5150 3725);
DISPLAY INVISIBLE (-5150 3725);
FORCEADD Q_RES..1
(-5275 1950);
FORCEPROP 1 LAST PART_NUMBER CS04992FB07
J 0
(-5175 1925);
DISPLAY 0.404255 (-5175 1925);
DISPLAY INVISIBLE (-5175 1925);
FORCEPROP 1 LAST VALUE 49.9
J 2
(-5050 1950);
DISPLAY 0.510638 (-5050 1950);
FORCEPROP 1 LAST MATERIAL CHIP
J 0
(-5450 1900);
DISPLAY 0.404255 (-5450 1900);
FORCEPROP 1 LAST $LOCATION R3894
J 0
(-5525 1950);
DISPLAY 0.638298 (-5525 1950);
FORCEPROP 1 LASTPIN (-5375 1950) $PN 1
J 0
(-5363 1962);
DISPLAY 0.787234 (-5363 1962);
PAINT MONO (-5363 1962);
FORCEPROP 1 LASTPIN (-5175 1950) $PN 2
J 0
(-5213 1962);
DISPLAY 0.787234 (-5213 1962);
PAINT MONO (-5213 1962);
FORCEPROP 2 LAST CDS_LIB pure_quanta
J 0
(-5275 1950);
DISPLAY INVISIBLE (-5275 1950);
FORCEPROP 1 LAST PACK_TYPE 0402LF
J 0
(-4975 1950);
DISPLAY 0.510638 (-4975 1950);
DISPLAY INVISIBLE (-4975 1950);
FORCEPROP 1 LAST TOLERANCE 1%
J 0
(-5050 1950);
DISPLAY 0.510638 (-5050 1950);
DISPLAY INVISIBLE (-5050 1950);
FORCEPROP 1 LAST WATTAGE 1/16W
J 2
(-4975 1900);
DISPLAY 0.404255 (-4975 1900);
DISPLAY INVISIBLE (-4975 1900);
FORCEPROP 1 LAST PATH I180
J 0
(-5325 2100);
DISPLAY 0.978723 (-5325 2100);
PAINT WHITE (-5325 2100);
DISPLAY INVISIBLE (-5325 2100);
FORCEPROP 0 LAST CDS_LOCATION R3894
J 0
(-5425 2000);
DISPLAY 1.021277 (-5425 2000);
DISPLAY INVISIBLE (-5425 2000);
FORCEPROP 0 LAST $SEC 1
J 0
(-5425 2000);
DISPLAY 0.680851 (-5425 2000);
PAINT MONO (-5425 2000);
DISPLAY INVISIBLE (-5425 2000);
FORCEPROP 0 LAST CDS_SEC 1
J 0
(-5425 2000);
DISPLAY 1.021277 (-5425 2000);
DISPLAY INVISIBLE (-5425 2000);
FORCEADD OFFPAGE..1
(-5200 3850);
FORCEPROP 2 LAST $XR1 100 
J 0
(-5541 3850);
DISPLAY 0.638298 (-5541 3850);
PAINT MONO (-5541 3850);
FORCEPROP 2 LAST $XR0 52 
J 0
(-5421 3850);
DISPLAY 0.638298 (-5421 3850);
PAINT MONO (-5421 3850);
FORCEPROP 2 LAST CDS_LIB standard
J 0
(-5200 3850);
PAINT MONO (-5200 3850);
DISPLAY INVISIBLE (-5200 3850);
FORCEPROP 1 LAST OFFPAGE TRUE
J 0
(-4875 3725);
DISPLAY 0.872340 (-4875 3725);
DISPLAY INVISIBLE (-4875 3725);
FORCEPROP 1 LAST COMMENT_BODY TRUE
J 0
(-5075 3750);
DISPLAY 0.872340 (-5075 3750);
PAINT GREEN (-5075 3750);
DISPLAY INVISIBLE (-5075 3750);
FORCEPROP 2 LAST PATH I19
J 0
(-5150 3925);
DISPLAY 1.021277 (-5150 3925);
DISPLAY INVISIBLE (-5150 3925);
FORCEADD OFFPAGE..2
R 2
(-5200 1200);
FORCEPROP 2 LAST $XR0 52 
J 0
(-5424 1200);
DISPLAY 0.638298 (-5424 1200);
PAINT MONO (-5424 1200);
FORCEPROP 2 LAST CDS_LIB standard
J 0
(-5200 1200);
PAINT MONO (-5200 1200);
DISPLAY INVISIBLE (-5200 1200);
FORCEPROP 1 LAST OFFPAGE TRUE
J 2
(-5525 1075);
DISPLAY 0.872340 (-5525 1075);
DISPLAY INVISIBLE (-5525 1075);
FORCEPROP 1 LAST COMMENT_BODY TRUE
J 2
(-5155 1105);
DISPLAY 0.872340 (-5155 1105);
PAINT GREEN (-5155 1105);
DISPLAY INVISIBLE (-5155 1105);
FORCEPROP 2 LAST PATH I2
J 0
(-5150 1275);
DISPLAY 1.021277 (-5150 1275);
DISPLAY INVISIBLE (-5150 1275);
FORCEADD OFFPAGE..1
(-5200 4275);
FORCEPROP 2 LAST $XR1 100 
J 0
(-5541 4275);
DISPLAY 0.638298 (-5541 4275);
PAINT MONO (-5541 4275);
FORCEPROP 2 LAST $XR0 52 
J 0
(-5421 4275);
DISPLAY 0.638298 (-5421 4275);
PAINT MONO (-5421 4275);
FORCEPROP 2 LAST CDS_LIB standard
J 0
(-5200 4275);
PAINT MONO (-5200 4275);
DISPLAY INVISIBLE (-5200 4275);
FORCEPROP 1 LAST OFFPAGE TRUE
J 0
(-4875 4150);
DISPLAY 0.872340 (-4875 4150);
DISPLAY INVISIBLE (-4875 4150);
FORCEPROP 1 LAST COMMENT_BODY TRUE
J 0
(-5075 4175);
DISPLAY 0.872340 (-5075 4175);
PAINT GREEN (-5075 4175);
DISPLAY INVISIBLE (-5075 4175);
FORCEPROP 2 LAST PATH I20
J 0
(-5150 4350);
DISPLAY 1.021277 (-5150 4350);
DISPLAY INVISIBLE (-5150 4350);
FORCEADD VCC_CORE..1
(-5100 2525);
FORCEPROP 3 LASTPIN (-5100 2475) SIG_NAME P3V3_AUX\g
J 0
(-5090 2485);
DISPLAY 0.659574 (-5090 2485);
PAINT MONO (-5090 2485);
DISPLAY INVISIBLE (-5090 2485);
FORCEPROP 1 LAST HDL_POWER P3V3_AUX
J 1
(-5100 2575);
DISPLAY 1.148936 (-5100 2575);
PAINT GREEN (-5100 2575);
FORCEPROP 2 LAST CDS_LIB logical_power
J 0
(-5100 2525);
PAINT MONO (-5100 2525);
DISPLAY INVISIBLE (-5100 2525);
FORCEPROP 1 LAST PATH I21
J 0
(-5050 2550);
DISPLAY 0.872340 (-5050 2550);
PAINT AQUA (-5050 2550);
DISPLAY INVISIBLE (-5050 2550);
FORCEADD TAP..1
R 2
(-4275 2450);
FORCEPROP 3 LASTPIN (-4225 2450) SIG_NAME M_B_CPU1_SB_CB<0>
J 0
(-4215 2460);
DISPLAY 0.659574 (-4215 2460);
PAINT MONO (-4215 2460);
DISPLAY INVISIBLE (-4215 2460);
FORCEPROP 1 LASTPIN (-4225 2450) BN 0
J 2
(-4213 2458);
DISPLAY 0.680851 (-4213 2458);
PAINT GREEN (-4213 2458);
FORCEPROP 2 LAST CDS_LIB standard
J 0
(-4275 2450);
PAINT MONO (-4275 2450);
DISPLAY INVISIBLE (-4275 2450);
FORCEPROP 1 LAST BODY_TYPE PLUMBING
J 2
(-4275 2500);
DISPLAY 0.872340 (-4275 2500);
PAINT GREEN (-4275 2500);
DISPLAY INVISIBLE (-4275 2500);
FORCEPROP 1 LAST HDL_TAP TRUE
J 2
(-4600 2325);
DISPLAY 0.872340 (-4600 2325);
DISPLAY INVISIBLE (-4600 2325);
FORCEPROP 1 LAST PATH I22
J 2
(-4273 2450);
DISPLAY 0.872340 (-4273 2450);
PAINT GREEN (-4273 2450);
DISPLAY INVISIBLE (-4273 2450);
FORCEADD TAP..1
R 2
(-4275 2500);
FORCEPROP 3 LASTPIN (-4225 2500) SIG_NAME M_B_CPU1_SB_CB<1>
J 0
(-4215 2510);
DISPLAY 0.659574 (-4215 2510);
PAINT MONO (-4215 2510);
DISPLAY INVISIBLE (-4215 2510);
FORCEPROP 1 LASTPIN (-4225 2500) BN 1
J 2
(-4213 2508);
DISPLAY 0.680851 (-4213 2508);
PAINT GREEN (-4213 2508);
FORCEPROP 2 LAST CDS_LIB standard
J 0
(-4275 2500);
DISPLAY INVISIBLE (-4275 2500);
FORCEPROP 1 LAST BODY_TYPE PLUMBING
J 2
(-4275 2550);
DISPLAY 0.872340 (-4275 2550);
PAINT GREEN (-4275 2550);
DISPLAY INVISIBLE (-4275 2550);
FORCEPROP 1 LAST HDL_TAP TRUE
J 2
(-4600 2375);
DISPLAY 0.872340 (-4600 2375);
DISPLAY INVISIBLE (-4600 2375);
FORCEPROP 1 LAST PATH I23
J 2
(-4273 2500);
DISPLAY 0.872340 (-4273 2500);
PAINT GREEN (-4273 2500);
DISPLAY INVISIBLE (-4273 2500);
FORCEADD TAP..1
R 2
(-4275 2550);
FORCEPROP 3 LASTPIN (-4225 2550) SIG_NAME M_B_CPU1_SB_CB<2>
J 0
(-4215 2560);
DISPLAY 0.659574 (-4215 2560);
PAINT MONO (-4215 2560);
DISPLAY INVISIBLE (-4215 2560);
FORCEPROP 1 LASTPIN (-4225 2550) BN 2
J 2
(-4213 2558);
DISPLAY 0.680851 (-4213 2558);
PAINT GREEN (-4213 2558);
FORCEPROP 2 LAST CDS_LIB standard
J 0
(-4275 2550);
DISPLAY INVISIBLE (-4275 2550);
FORCEPROP 1 LAST BODY_TYPE PLUMBING
J 2
(-4275 2600);
DISPLAY 0.872340 (-4275 2600);
PAINT GREEN (-4275 2600);
DISPLAY INVISIBLE (-4275 2600);
FORCEPROP 1 LAST HDL_TAP TRUE
J 2
(-4600 2425);
DISPLAY 0.872340 (-4600 2425);
DISPLAY INVISIBLE (-4600 2425);
FORCEPROP 1 LAST PATH I24
J 2
(-4273 2550);
DISPLAY 0.872340 (-4273 2550);
PAINT GREEN (-4273 2550);
DISPLAY INVISIBLE (-4273 2550);
FORCEADD TAP..1
R 2
(-4275 2600);
FORCEPROP 3 LASTPIN (-4225 2600) SIG_NAME M_B_CPU1_SB_CB<3>
J 0
(-4215 2610);
DISPLAY 0.659574 (-4215 2610);
PAINT MONO (-4215 2610);
DISPLAY INVISIBLE (-4215 2610);
FORCEPROP 1 LASTPIN (-4225 2600) BN 3
J 2
(-4213 2608);
DISPLAY 0.680851 (-4213 2608);
PAINT GREEN (-4213 2608);
FORCEPROP 2 LAST CDS_LIB standard
J 0
(-4275 2600);
DISPLAY INVISIBLE (-4275 2600);
FORCEPROP 1 LAST BODY_TYPE PLUMBING
J 2
(-4275 2650);
DISPLAY 0.872340 (-4275 2650);
PAINT GREEN (-4275 2650);
DISPLAY INVISIBLE (-4275 2650);
FORCEPROP 1 LAST HDL_TAP TRUE
J 2
(-4600 2475);
DISPLAY 0.872340 (-4600 2475);
DISPLAY INVISIBLE (-4600 2475);
FORCEPROP 1 LAST PATH I25
J 2
(-4273 2600);
DISPLAY 0.872340 (-4273 2600);
PAINT GREEN (-4273 2600);
DISPLAY INVISIBLE (-4273 2600);
FORCEADD TAP..1
R 2
(-4275 2650);
FORCEPROP 3 LASTPIN (-4225 2650) SIG_NAME M_B_CPU1_SB_CB<4>
J 0
(-4215 2660);
DISPLAY 0.659574 (-4215 2660);
PAINT MONO (-4215 2660);
DISPLAY INVISIBLE (-4215 2660);
FORCEPROP 1 LASTPIN (-4225 2650) BN 4
J 2
(-4213 2658);
DISPLAY 0.680851 (-4213 2658);
PAINT GREEN (-4213 2658);
FORCEPROP 2 LAST CDS_LIB standard
J 0
(-4275 2650);
DISPLAY INVISIBLE (-4275 2650);
FORCEPROP 1 LAST BODY_TYPE PLUMBING
J 2
(-4275 2700);
DISPLAY 0.872340 (-4275 2700);
PAINT GREEN (-4275 2700);
DISPLAY INVISIBLE (-4275 2700);
FORCEPROP 1 LAST HDL_TAP TRUE
J 2
(-4600 2525);
DISPLAY 0.872340 (-4600 2525);
DISPLAY INVISIBLE (-4600 2525);
FORCEPROP 1 LAST PATH I26
J 2
(-4273 2650);
DISPLAY 0.872340 (-4273 2650);
PAINT GREEN (-4273 2650);
DISPLAY INVISIBLE (-4273 2650);
FORCEADD TAP..1
R 2
(-4275 2700);
FORCEPROP 3 LASTPIN (-4225 2700) SIG_NAME M_B_CPU1_SB_CB<5>
J 0
(-4215 2710);
DISPLAY 0.659574 (-4215 2710);
PAINT MONO (-4215 2710);
DISPLAY INVISIBLE (-4215 2710);
FORCEPROP 1 LASTPIN (-4225 2700) BN 5
J 2
(-4213 2708);
DISPLAY 0.680851 (-4213 2708);
PAINT GREEN (-4213 2708);
FORCEPROP 2 LAST CDS_LIB standard
J 0
(-4275 2700);
DISPLAY INVISIBLE (-4275 2700);
FORCEPROP 1 LAST BODY_TYPE PLUMBING
J 2
(-4275 2750);
DISPLAY 0.872340 (-4275 2750);
PAINT GREEN (-4275 2750);
DISPLAY INVISIBLE (-4275 2750);
FORCEPROP 1 LAST HDL_TAP TRUE
J 2
(-4600 2575);
DISPLAY 0.872340 (-4600 2575);
DISPLAY INVISIBLE (-4600 2575);
FORCEPROP 1 LAST PATH I27
J 2
(-4273 2700);
DISPLAY 0.872340 (-4273 2700);
PAINT GREEN (-4273 2700);
DISPLAY INVISIBLE (-4273 2700);
FORCEADD TAP..1
R 2
(-4275 2750);
FORCEPROP 3 LASTPIN (-4225 2750) SIG_NAME M_B_CPU1_SB_CB<6>
J 0
(-4215 2760);
DISPLAY 0.659574 (-4215 2760);
PAINT MONO (-4215 2760);
DISPLAY INVISIBLE (-4215 2760);
FORCEPROP 1 LASTPIN (-4225 2750) BN 6
J 2
(-4213 2758);
DISPLAY 0.680851 (-4213 2758);
PAINT GREEN (-4213 2758);
FORCEPROP 2 LAST CDS_LIB standard
J 0
(-4275 2750);
DISPLAY INVISIBLE (-4275 2750);
FORCEPROP 1 LAST BODY_TYPE PLUMBING
J 2
(-4275 2800);
DISPLAY 0.872340 (-4275 2800);
PAINT GREEN (-4275 2800);
DISPLAY INVISIBLE (-4275 2800);
FORCEPROP 1 LAST HDL_TAP TRUE
J 2
(-4600 2625);
DISPLAY 0.872340 (-4600 2625);
DISPLAY INVISIBLE (-4600 2625);
FORCEPROP 1 LAST PATH I28
J 2
(-4273 2750);
DISPLAY 0.872340 (-4273 2750);
PAINT GREEN (-4273 2750);
DISPLAY INVISIBLE (-4273 2750);
FORCEADD TAP..1
R 2
(-4275 2800);
FORCEPROP 3 LASTPIN (-4225 2800) SIG_NAME M_B_CPU1_SB_CB<7>
J 0
(-4215 2810);
DISPLAY 0.659574 (-4215 2810);
PAINT MONO (-4215 2810);
DISPLAY INVISIBLE (-4215 2810);
FORCEPROP 1 LASTPIN (-4225 2800) BN 7
J 2
(-4213 2808);
DISPLAY 0.680851 (-4213 2808);
PAINT GREEN (-4213 2808);
FORCEPROP 2 LAST CDS_LIB standard
J 0
(-4275 2800);
DISPLAY INVISIBLE (-4275 2800);
FORCEPROP 1 LAST BODY_TYPE PLUMBING
J 2
(-4275 2850);
DISPLAY 0.872340 (-4275 2850);
PAINT GREEN (-4275 2850);
DISPLAY INVISIBLE (-4275 2850);
FORCEPROP 1 LAST HDL_TAP TRUE
J 2
(-4600 2675);
DISPLAY 0.872340 (-4600 2675);
DISPLAY INVISIBLE (-4600 2675);
FORCEPROP 1 LAST PATH I29
J 2
(-4273 2800);
DISPLAY 0.872340 (-4273 2800);
PAINT GREEN (-4273 2800);
DISPLAY INVISIBLE (-4273 2800);
FORCEADD OFFPAGE..2
R 2
(-5200 1250);
FORCEPROP 2 LAST $XR0 52 
J 0
(-5424 1250);
DISPLAY 0.638298 (-5424 1250);
PAINT MONO (-5424 1250);
FORCEPROP 2 LAST CDS_LIB standard
J 0
(-5200 1250);
PAINT MONO (-5200 1250);
DISPLAY INVISIBLE (-5200 1250);
FORCEPROP 1 LAST OFFPAGE TRUE
J 2
(-5525 1125);
DISPLAY 0.872340 (-5525 1125);
DISPLAY INVISIBLE (-5525 1125);
FORCEPROP 1 LAST COMMENT_BODY TRUE
J 2
(-5155 1155);
DISPLAY 0.872340 (-5155 1155);
PAINT GREEN (-5155 1155);
DISPLAY INVISIBLE (-5155 1155);
FORCEPROP 2 LAST PATH I3
J 0
(-5150 1325);
DISPLAY 1.021277 (-5150 1325);
DISPLAY INVISIBLE (-5150 1325);
FORCEADD TAP..1
R 2
(-4275 2900);
FORCEPROP 3 LASTPIN (-4225 2900) SIG_NAME M_B_CPU1_SA_CB<0>
J 0
(-4215 2910);
DISPLAY 0.659574 (-4215 2910);
PAINT MONO (-4215 2910);
DISPLAY INVISIBLE (-4215 2910);
FORCEPROP 1 LASTPIN (-4225 2900) BN 0
J 2
(-4213 2908);
DISPLAY 0.680851 (-4213 2908);
PAINT GREEN (-4213 2908);
FORCEPROP 2 LAST CDS_LIB standard
J 0
(-4275 2900);
PAINT MONO (-4275 2900);
DISPLAY INVISIBLE (-4275 2900);
FORCEPROP 1 LAST BODY_TYPE PLUMBING
J 2
(-4275 2950);
DISPLAY 0.872340 (-4275 2950);
PAINT GREEN (-4275 2950);
DISPLAY INVISIBLE (-4275 2950);
FORCEPROP 1 LAST HDL_TAP TRUE
J 2
(-4600 2775);
DISPLAY 0.872340 (-4600 2775);
DISPLAY INVISIBLE (-4600 2775);
FORCEPROP 1 LAST PATH I30
J 2
(-4273 2900);
DISPLAY 0.872340 (-4273 2900);
PAINT GREEN (-4273 2900);
DISPLAY INVISIBLE (-4273 2900);
FORCEADD TAP..1
R 2
(-4275 3000);
FORCEPROP 3 LASTPIN (-4225 3000) SIG_NAME M_B_CPU1_SA_CB<2>
J 0
(-4215 3010);
DISPLAY 0.659574 (-4215 3010);
PAINT MONO (-4215 3010);
DISPLAY INVISIBLE (-4215 3010);
FORCEPROP 1 LASTPIN (-4225 3000) BN 2
J 2
(-4213 3008);
DISPLAY 0.680851 (-4213 3008);
PAINT GREEN (-4213 3008);
FORCEPROP 2 LAST CDS_LIB standard
J 0
(-4275 3000);
DISPLAY INVISIBLE (-4275 3000);
FORCEPROP 1 LAST BODY_TYPE PLUMBING
J 2
(-4275 3050);
DISPLAY 0.872340 (-4275 3050);
PAINT GREEN (-4275 3050);
DISPLAY INVISIBLE (-4275 3050);
FORCEPROP 1 LAST HDL_TAP TRUE
J 2
(-4600 2875);
DISPLAY 0.872340 (-4600 2875);
DISPLAY INVISIBLE (-4600 2875);
FORCEPROP 1 LAST PATH I31
J 2
(-4273 3000);
DISPLAY 0.872340 (-4273 3000);
PAINT GREEN (-4273 3000);
DISPLAY INVISIBLE (-4273 3000);
FORCEADD TAP..1
R 2
(-4275 2950);
FORCEPROP 3 LASTPIN (-4225 2950) SIG_NAME M_B_CPU1_SA_CB<1>
J 0
(-4215 2960);
DISPLAY 0.659574 (-4215 2960);
PAINT MONO (-4215 2960);
DISPLAY INVISIBLE (-4215 2960);
FORCEPROP 1 LASTPIN (-4225 2950) BN 1
J 2
(-4213 2958);
DISPLAY 0.680851 (-4213 2958);
PAINT GREEN (-4213 2958);
FORCEPROP 2 LAST CDS_LIB standard
J 0
(-4275 2950);
DISPLAY INVISIBLE (-4275 2950);
FORCEPROP 1 LAST BODY_TYPE PLUMBING
J 2
(-4275 3000);
DISPLAY 0.872340 (-4275 3000);
PAINT GREEN (-4275 3000);
DISPLAY INVISIBLE (-4275 3000);
FORCEPROP 1 LAST HDL_TAP TRUE
J 2
(-4600 2825);
DISPLAY 0.872340 (-4600 2825);
DISPLAY INVISIBLE (-4600 2825);
FORCEPROP 1 LAST PATH I32
J 2
(-4273 2950);
DISPLAY 0.872340 (-4273 2950);
PAINT GREEN (-4273 2950);
DISPLAY INVISIBLE (-4273 2950);
FORCEADD TAP..1
R 2
(-4275 3050);
FORCEPROP 3 LASTPIN (-4225 3050) SIG_NAME M_B_CPU1_SA_CB<3>
J 0
(-4215 3060);
DISPLAY 0.659574 (-4215 3060);
PAINT MONO (-4215 3060);
DISPLAY INVISIBLE (-4215 3060);
FORCEPROP 1 LASTPIN (-4225 3050) BN 3
J 2
(-4213 3058);
DISPLAY 0.680851 (-4213 3058);
PAINT GREEN (-4213 3058);
FORCEPROP 2 LAST CDS_LIB standard
J 0
(-4275 3050);
DISPLAY INVISIBLE (-4275 3050);
FORCEPROP 1 LAST BODY_TYPE PLUMBING
J 2
(-4275 3100);
DISPLAY 0.872340 (-4275 3100);
PAINT GREEN (-4275 3100);
DISPLAY INVISIBLE (-4275 3100);
FORCEPROP 1 LAST HDL_TAP TRUE
J 2
(-4600 2925);
DISPLAY 0.872340 (-4600 2925);
DISPLAY INVISIBLE (-4600 2925);
FORCEPROP 1 LAST PATH I33
J 2
(-4273 3050);
DISPLAY 0.872340 (-4273 3050);
PAINT GREEN (-4273 3050);
DISPLAY INVISIBLE (-4273 3050);
FORCEADD TAP..1
R 2
(-4275 3100);
FORCEPROP 3 LASTPIN (-4225 3100) SIG_NAME M_B_CPU1_SA_CB<4>
J 0
(-4215 3110);
DISPLAY 0.659574 (-4215 3110);
PAINT MONO (-4215 3110);
DISPLAY INVISIBLE (-4215 3110);
FORCEPROP 1 LASTPIN (-4225 3100) BN 4
J 2
(-4213 3108);
DISPLAY 0.680851 (-4213 3108);
PAINT GREEN (-4213 3108);
FORCEPROP 2 LAST CDS_LIB standard
J 0
(-4275 3100);
DISPLAY INVISIBLE (-4275 3100);
FORCEPROP 1 LAST BODY_TYPE PLUMBING
J 2
(-4275 3150);
DISPLAY 0.872340 (-4275 3150);
PAINT GREEN (-4275 3150);
DISPLAY INVISIBLE (-4275 3150);
FORCEPROP 1 LAST HDL_TAP TRUE
J 2
(-4600 2975);
DISPLAY 0.872340 (-4600 2975);
DISPLAY INVISIBLE (-4600 2975);
FORCEPROP 1 LAST PATH I34
J 2
(-4273 3100);
DISPLAY 0.872340 (-4273 3100);
PAINT GREEN (-4273 3100);
DISPLAY INVISIBLE (-4273 3100);
FORCEADD TAP..1
R 2
(-4275 3150);
FORCEPROP 3 LASTPIN (-4225 3150) SIG_NAME M_B_CPU1_SA_CB<5>
J 0
(-4215 3160);
DISPLAY 0.659574 (-4215 3160);
PAINT MONO (-4215 3160);
DISPLAY INVISIBLE (-4215 3160);
FORCEPROP 1 LASTPIN (-4225 3150) BN 5
J 2
(-4213 3158);
DISPLAY 0.680851 (-4213 3158);
PAINT GREEN (-4213 3158);
FORCEPROP 2 LAST CDS_LIB standard
J 0
(-4275 3150);
DISPLAY INVISIBLE (-4275 3150);
FORCEPROP 1 LAST BODY_TYPE PLUMBING
J 2
(-4275 3200);
DISPLAY 0.872340 (-4275 3200);
PAINT GREEN (-4275 3200);
DISPLAY INVISIBLE (-4275 3200);
FORCEPROP 1 LAST HDL_TAP TRUE
J 2
(-4600 3025);
DISPLAY 0.872340 (-4600 3025);
DISPLAY INVISIBLE (-4600 3025);
FORCEPROP 1 LAST PATH I35
J 2
(-4273 3150);
DISPLAY 0.872340 (-4273 3150);
PAINT GREEN (-4273 3150);
DISPLAY INVISIBLE (-4273 3150);
FORCEADD TAP..1
R 2
(-4275 3200);
FORCEPROP 3 LASTPIN (-4225 3200) SIG_NAME M_B_CPU1_SA_CB<6>
J 0
(-4215 3210);
DISPLAY 0.659574 (-4215 3210);
PAINT MONO (-4215 3210);
DISPLAY INVISIBLE (-4215 3210);
FORCEPROP 1 LASTPIN (-4225 3200) BN 6
J 2
(-4213 3208);
DISPLAY 0.680851 (-4213 3208);
PAINT GREEN (-4213 3208);
FORCEPROP 2 LAST CDS_LIB standard
J 0
(-4275 3200);
DISPLAY INVISIBLE (-4275 3200);
FORCEPROP 1 LAST BODY_TYPE PLUMBING
J 2
(-4275 3250);
DISPLAY 0.872340 (-4275 3250);
PAINT GREEN (-4275 3250);
DISPLAY INVISIBLE (-4275 3250);
FORCEPROP 1 LAST HDL_TAP TRUE
J 2
(-4600 3075);
DISPLAY 0.872340 (-4600 3075);
DISPLAY INVISIBLE (-4600 3075);
FORCEPROP 1 LAST PATH I36
J 2
(-4273 3200);
DISPLAY 0.872340 (-4273 3200);
PAINT GREEN (-4273 3200);
DISPLAY INVISIBLE (-4273 3200);
FORCEADD TAP..1
R 2
(-4275 3250);
FORCEPROP 3 LASTPIN (-4225 3250) SIG_NAME M_B_CPU1_SA_CB<7>
J 0
(-4215 3260);
DISPLAY 0.659574 (-4215 3260);
PAINT MONO (-4215 3260);
DISPLAY INVISIBLE (-4215 3260);
FORCEPROP 1 LASTPIN (-4225 3250) BN 7
J 2
(-4213 3258);
DISPLAY 0.680851 (-4213 3258);
PAINT GREEN (-4213 3258);
FORCEPROP 2 LAST CDS_LIB standard
J 0
(-4275 3250);
DISPLAY INVISIBLE (-4275 3250);
FORCEPROP 1 LAST BODY_TYPE PLUMBING
J 2
(-4275 3300);
DISPLAY 0.872340 (-4275 3300);
PAINT GREEN (-4275 3300);
DISPLAY INVISIBLE (-4275 3300);
FORCEPROP 1 LAST HDL_TAP TRUE
J 2
(-4600 3125);
DISPLAY 0.872340 (-4600 3125);
DISPLAY INVISIBLE (-4600 3125);
FORCEPROP 1 LAST PATH I37
J 2
(-4273 3250);
DISPLAY 0.872340 (-4273 3250);
PAINT GREEN (-4273 3250);
DISPLAY INVISIBLE (-4273 3250);
FORCEADD TAP..1
R 2
(-4275 3950);
FORCEPROP 3 LASTPIN (-4225 3950) SIG_NAME M_B_CPU1_SB_CA<0>
J 0
(-4215 3960);
DISPLAY 0.659574 (-4215 3960);
PAINT MONO (-4215 3960);
DISPLAY INVISIBLE (-4215 3960);
FORCEPROP 1 LASTPIN (-4225 3950) BN 0
J 2
(-4213 3958);
DISPLAY 0.680851 (-4213 3958);
PAINT GREEN (-4213 3958);
FORCEPROP 2 LAST CDS_LIB standard
J 0
(-4275 3950);
DISPLAY INVISIBLE (-4275 3950);
FORCEPROP 1 LAST BODY_TYPE PLUMBING
J 2
(-4275 4000);
DISPLAY 0.872340 (-4275 4000);
PAINT GREEN (-4275 4000);
DISPLAY INVISIBLE (-4275 4000);
FORCEPROP 1 LAST HDL_TAP TRUE
J 2
(-4600 3825);
DISPLAY 0.872340 (-4600 3825);
DISPLAY INVISIBLE (-4600 3825);
FORCEPROP 1 LAST PATH I38
J 2
(-4273 3950);
DISPLAY 0.872340 (-4273 3950);
PAINT GREEN (-4273 3950);
DISPLAY INVISIBLE (-4273 3950);
FORCEADD TAP..1
R 2
(-4275 4000);
FORCEPROP 3 LASTPIN (-4225 4000) SIG_NAME M_B_CPU1_SB_CA<1>
J 0
(-4215 4010);
DISPLAY 0.659574 (-4215 4010);
PAINT MONO (-4215 4010);
DISPLAY INVISIBLE (-4215 4010);
FORCEPROP 1 LASTPIN (-4225 4000) BN 1
J 2
(-4213 4008);
DISPLAY 0.680851 (-4213 4008);
PAINT GREEN (-4213 4008);
FORCEPROP 2 LAST CDS_LIB standard
J 0
(-4275 4000);
DISPLAY INVISIBLE (-4275 4000);
FORCEPROP 1 LAST BODY_TYPE PLUMBING
J 2
(-4275 4050);
DISPLAY 0.872340 (-4275 4050);
PAINT GREEN (-4275 4050);
DISPLAY INVISIBLE (-4275 4050);
FORCEPROP 1 LAST HDL_TAP TRUE
J 2
(-4600 3875);
DISPLAY 0.872340 (-4600 3875);
DISPLAY INVISIBLE (-4600 3875);
FORCEPROP 1 LAST PATH I39
J 2
(-4273 4000);
DISPLAY 0.872340 (-4273 4000);
PAINT GREEN (-4273 4000);
DISPLAY INVISIBLE (-4273 4000);
FORCEADD OFFPAGE..3
R 2
(-5200 1800);
FORCEPROP 2 LAST $XR0 114 
J 0
(-5480 1800);
DISPLAY 0.638298 (-5480 1800);
PAINT MONO (-5480 1800);
FORCEPROP 2 LAST CDS_LIB standard
J 0
(-5200 1800);
PAINT MONO (-5200 1800);
DISPLAY INVISIBLE (-5200 1800);
FORCEPROP 1 LAST OFFPAGE TRUE
J 2
(-5525 1675);
DISPLAY 0.872340 (-5525 1675);
DISPLAY INVISIBLE (-5525 1675);
FORCEPROP 1 LAST COMMENT_BODY TRUE
J 2
(-5150 1700);
DISPLAY 0.872340 (-5150 1700);
PAINT GREEN (-5150 1700);
DISPLAY INVISIBLE (-5150 1700);
FORCEPROP 2 LAST PATH I4
J 0
(-5150 1875);
DISPLAY 1.021277 (-5150 1875);
DISPLAY INVISIBLE (-5150 1875);
FORCEADD TAP..1
R 2
(-4275 4050);
FORCEPROP 3 LASTPIN (-4225 4050) SIG_NAME M_B_CPU1_SB_CA<2>
J 0
(-4215 4060);
DISPLAY 0.659574 (-4215 4060);
PAINT MONO (-4215 4060);
DISPLAY INVISIBLE (-4215 4060);
FORCEPROP 1 LASTPIN (-4225 4050) BN 2
J 2
(-4213 4058);
DISPLAY 0.680851 (-4213 4058);
PAINT GREEN (-4213 4058);
FORCEPROP 2 LAST CDS_LIB standard
J 0
(-4275 4050);
DISPLAY INVISIBLE (-4275 4050);
FORCEPROP 1 LAST BODY_TYPE PLUMBING
J 2
(-4275 4100);
DISPLAY 0.872340 (-4275 4100);
PAINT GREEN (-4275 4100);
DISPLAY INVISIBLE (-4275 4100);
FORCEPROP 1 LAST HDL_TAP TRUE
J 2
(-4600 3925);
DISPLAY 0.872340 (-4600 3925);
DISPLAY INVISIBLE (-4600 3925);
FORCEPROP 1 LAST PATH I40
J 2
(-4273 4050);
DISPLAY 0.872340 (-4273 4050);
PAINT GREEN (-4273 4050);
DISPLAY INVISIBLE (-4273 4050);
FORCEADD TAP..1
R 2
(-4275 4150);
FORCEPROP 3 LASTPIN (-4225 4150) SIG_NAME M_B_CPU1_SB_CA<4>
J 0
(-4215 4160);
DISPLAY 0.659574 (-4215 4160);
PAINT MONO (-4215 4160);
DISPLAY INVISIBLE (-4215 4160);
FORCEPROP 1 LASTPIN (-4225 4150) BN 4
J 2
(-4213 4158);
DISPLAY 0.680851 (-4213 4158);
PAINT GREEN (-4213 4158);
FORCEPROP 2 LAST CDS_LIB standard
J 0
(-4275 4150);
DISPLAY INVISIBLE (-4275 4150);
FORCEPROP 1 LAST BODY_TYPE PLUMBING
J 2
(-4275 4200);
DISPLAY 0.872340 (-4275 4200);
PAINT GREEN (-4275 4200);
DISPLAY INVISIBLE (-4275 4200);
FORCEPROP 1 LAST HDL_TAP TRUE
J 2
(-4600 4025);
DISPLAY 0.872340 (-4600 4025);
DISPLAY INVISIBLE (-4600 4025);
FORCEPROP 1 LAST PATH I41
J 2
(-4273 4150);
DISPLAY 0.872340 (-4273 4150);
PAINT GREEN (-4273 4150);
DISPLAY INVISIBLE (-4273 4150);
FORCEADD TAP..1
R 2
(-4275 4250);
FORCEPROP 3 LASTPIN (-4225 4250) SIG_NAME M_B_CPU1_SB_CA<6>
J 0
(-4215 4260);
DISPLAY 0.659574 (-4215 4260);
PAINT MONO (-4215 4260);
DISPLAY INVISIBLE (-4215 4260);
FORCEPROP 1 LASTPIN (-4225 4250) BN 6
J 2
(-4213 4258);
DISPLAY 0.680851 (-4213 4258);
PAINT GREEN (-4213 4258);
FORCEPROP 2 LAST CDS_LIB standard
J 0
(-4275 4250);
DISPLAY INVISIBLE (-4275 4250);
FORCEPROP 1 LAST BODY_TYPE PLUMBING
J 2
(-4275 4300);
DISPLAY 0.872340 (-4275 4300);
PAINT GREEN (-4275 4300);
DISPLAY INVISIBLE (-4275 4300);
FORCEPROP 1 LAST HDL_TAP TRUE
J 2
(-4600 4125);
DISPLAY 0.872340 (-4600 4125);
DISPLAY INVISIBLE (-4600 4125);
FORCEPROP 1 LAST PATH I42
J 2
(-4273 4250);
DISPLAY 0.872340 (-4273 4250);
PAINT GREEN (-4273 4250);
DISPLAY INVISIBLE (-4273 4250);
FORCEADD TAP..1
R 2
(-4275 4200);
FORCEPROP 3 LASTPIN (-4225 4200) SIG_NAME M_B_CPU1_SB_CA<5>
J 0
(-4215 4210);
DISPLAY 0.659574 (-4215 4210);
PAINT MONO (-4215 4210);
DISPLAY INVISIBLE (-4215 4210);
FORCEPROP 1 LASTPIN (-4225 4200) BN 5
J 2
(-4213 4208);
DISPLAY 0.680851 (-4213 4208);
PAINT GREEN (-4213 4208);
FORCEPROP 2 LAST CDS_LIB standard
J 0
(-4275 4200);
DISPLAY INVISIBLE (-4275 4200);
FORCEPROP 1 LAST BODY_TYPE PLUMBING
J 2
(-4275 4250);
DISPLAY 0.872340 (-4275 4250);
PAINT GREEN (-4275 4250);
DISPLAY INVISIBLE (-4275 4250);
FORCEPROP 1 LAST HDL_TAP TRUE
J 2
(-4600 4075);
DISPLAY 0.872340 (-4600 4075);
DISPLAY INVISIBLE (-4600 4075);
FORCEPROP 1 LAST PATH I43
J 2
(-4273 4200);
DISPLAY 0.872340 (-4273 4200);
PAINT GREEN (-4273 4200);
DISPLAY INVISIBLE (-4273 4200);
FORCEADD TAP..1
R 2
(-4275 4100);
FORCEPROP 3 LASTPIN (-4225 4100) SIG_NAME M_B_CPU1_SB_CA<3>
J 0
(-4215 4110);
DISPLAY 0.659574 (-4215 4110);
PAINT MONO (-4215 4110);
DISPLAY INVISIBLE (-4215 4110);
FORCEPROP 1 LASTPIN (-4225 4100) BN 3
J 2
(-4213 4108);
DISPLAY 0.680851 (-4213 4108);
PAINT GREEN (-4213 4108);
FORCEPROP 2 LAST CDS_LIB standard
J 0
(-4275 4100);
DISPLAY INVISIBLE (-4275 4100);
FORCEPROP 1 LAST BODY_TYPE PLUMBING
J 2
(-4275 4150);
DISPLAY 0.872340 (-4275 4150);
PAINT GREEN (-4275 4150);
DISPLAY INVISIBLE (-4275 4150);
FORCEPROP 1 LAST HDL_TAP TRUE
J 2
(-4600 3975);
DISPLAY 0.872340 (-4600 3975);
DISPLAY INVISIBLE (-4600 3975);
FORCEPROP 1 LAST PATH I44
J 2
(-4273 4100);
DISPLAY 0.872340 (-4273 4100);
PAINT GREEN (-4273 4100);
DISPLAY INVISIBLE (-4273 4100);
FORCEADD UNIVERSAL_GND..1
(-4050 275);
FORCEPROP 3 LASTPIN (-4050 325) SIG_NAME GND\g
J 0
(-4040 335);
DISPLAY 0.659574 (-4040 335);
PAINT MONO (-4040 335);
DISPLAY INVISIBLE (-4040 335);
FORCEPROP 1 LAST PATH I45
J 0
(-3975 275);
DISPLAY 0.872340 (-3975 275);
PAINT AQUA (-3975 275);
DISPLAY INVISIBLE (-3975 275);
FORCEPROP 1 LAST HDL_POWER GND
J 1
(-4025 200);
DISPLAY 0.872340 (-4025 200);
PAINT GREEN (-4025 200);
DISPLAY INVISIBLE (-4025 200);
FORCEPROP 2 LAST CDS_LIB logical_power
J 0
(-4050 275);
PAINT MONO (-4050 275);
DISPLAY INVISIBLE (-4050 275);
FORCEADD Q_RES..2
(-4050 500);
FORCEPROP 1 LAST PART_NUMBER CS33572FB01
J 0
(-4010 375);
DISPLAY 0.978723 (-4010 375);
DISPLAY INVISIBLE (-4010 375);
FORCEPROP 1 LAST VALUE 35.7K
J 0
(-4005 575);
DISPLAY 0.978723 (-4005 575);
FORCEPROP 1 LAST MATERIAL CHIP
J 0
(-4010 425);
DISPLAY 0.978723 (-4010 425);
FORCEPROP 1 LAST PACK_TYPE 0402LF
J 0
(-4010 325);
DISPLAY 0.978723 (-4010 325);
FORCEPROP 1 LAST WATTAGE 1/16W
J 0
(-4010 475);
DISPLAY 0.978723 (-4010 475);
FORCEPROP 1 LAST TOLERANCE 1%
J 0
(-4005 525);
DISPLAY 0.978723 (-4005 525);
FORCEPROP 1 LAST $LOCATION R45
J 0
(-4005 625);
DISPLAY 0.978723 (-4005 625);
FORCEPROP 1 LASTPIN (-4050 600) $PN 1
J 0
(-4045 562);
DISPLAY 0.787234 (-4045 562);
FORCEPROP 1 LASTPIN (-4050 400) $PN 2
J 0
(-4045 410);
DISPLAY 0.787234 (-4045 410);
FORCEPROP 2 LAST CDS_LIB pure_quanta
J 0
(-4050 500);
PAINT MONO (-4050 500);
DISPLAY INVISIBLE (-4050 500);
FORCEPROP 1 LAST PATH I46
J 0
(-4000 675);
DISPLAY 0.978723 (-4000 675);
PAINT WHITE (-4000 675);
DISPLAY INVISIBLE (-4000 675);
FORCEPROP 2 LAST CDS_LOCATION R45
J 0
(-4000 725);
DISPLAY 1.021277 (-4000 725);
DISPLAY INVISIBLE (-4000 725);
FORCEPROP 2 LAST $SEC 1
J 0
(-4000 725);
DISPLAY 0.680851 (-4000 725);
PAINT MONO (-4000 725);
DISPLAY INVISIBLE (-4000 725);
FORCEPROP 2 LAST CDS_SEC 1
J 0
(-4000 725);
DISPLAY 1.021277 (-4000 725);
DISPLAY INVISIBLE (-4000 725);
FORCEADD SCONN288_ADR50017P087CC..1
(-3450 2925);
FORCEPROP 1 LAST PART_NUMBER DFHST8FS460
J 0
(-3895 4935);
DISPLAY 0.723404 (-3895 4935);
PAINT GREEN (-3895 4935);
DISPLAY INVISIBLE (-3895 4935);
FORCEPROP 1 LAST MATERIAL IO
J 0
(-3895 4808);
DISPLAY 0.723404 (-3895 4808);
PAINT GREEN (-3895 4808);
FORCEPROP 2 LAST VALUE SCONN288_ADR50017-P087CC
J 0
(-3900 5050);
DISPLAY 1.021277 (-3900 5050);
FORCEPROP 2 LAST PART_TYPE SMLF
J 0
(-3900 5100);
DISPLAY 1.021277 (-3900 5100);
FORCEPROP 1 LAST $LOCATION J20
J 0
(-3900 5000);
DISPLAY 0.723404 (-3900 5000);
PAINT GREEN (-3900 5000);
FORCEPROP 0 LASTPIN (-4050 2300) $PN 62
J 2
(-4060 2310);
DISPLAY 0.680851 (-4060 2310);
PAINT MONO (-4060 2310);
FORCEPROP 0 LASTPIN (-4050 4350) $PN 66
J 2
(-4060 4360);
DISPLAY 0.680851 (-4060 4360);
PAINT MONO (-4060 4360);
FORCEPROP 0 LASTPIN (-4050 3950) $PN 76
J 2
(-4060 3960);
DISPLAY 0.680851 (-4060 3960);
PAINT MONO (-4060 3960);
FORCEPROP 0 LASTPIN (-4050 4400) $PN 211
J 2
(-4060 4410);
DISPLAY 0.680851 (-4060 4410);
PAINT MONO (-4060 4410);
FORCEPROP 0 LASTPIN (-4050 4000) $PN 221
J 2
(-4060 4010);
DISPLAY 0.680851 (-4060 4010);
PAINT MONO (-4060 4010);
FORCEPROP 0 LASTPIN (-4050 4450) $PN 68
J 2
(-4060 4460);
DISPLAY 0.680851 (-4060 4460);
PAINT MONO (-4060 4460);
FORCEPROP 0 LASTPIN (-4050 4050) $PN 78
J 2
(-4060 4060);
DISPLAY 0.680851 (-4060 4060);
PAINT MONO (-4060 4060);
FORCEPROP 0 LASTPIN (-4050 4500) $PN 213
J 2
(-4060 4510);
DISPLAY 0.680851 (-4060 4510);
PAINT MONO (-4060 4510);
FORCEPROP 0 LASTPIN (-4050 4100) $PN 223
J 2
(-4060 4110);
DISPLAY 0.680851 (-4060 4110);
PAINT MONO (-4060 4110);
FORCEPROP 0 LASTPIN (-4050 4550) $PN 70
J 2
(-4060 4560);
DISPLAY 0.680851 (-4060 4560);
PAINT MONO (-4060 4560);
FORCEPROP 0 LASTPIN (-4050 4150) $PN 80
J 2
(-4060 4160);
DISPLAY 0.680851 (-4060 4160);
PAINT MONO (-4060 4160);
FORCEPROP 0 LASTPIN (-4050 4600) $PN 215
J 2
(-4060 4610);
DISPLAY 0.680851 (-4060 4610);
PAINT MONO (-4060 4610);
FORCEPROP 0 LASTPIN (-4050 4200) $PN 225
J 2
(-4060 4210);
DISPLAY 0.680851 (-4060 4210);
PAINT MONO (-4060 4210);
FORCEPROP 0 LASTPIN (-4050 4650) $PN 72
J 2
(-4060 4660);
DISPLAY 0.680851 (-4060 4660);
PAINT MONO (-4060 4660);
FORCEPROP 0 LASTPIN (-4050 4250) $PN 82
J 2
(-4060 4260);
DISPLAY 0.680851 (-4060 4260);
PAINT MONO (-4060 4260);
FORCEPROP 0 LASTPIN (-4050 2900) $PN 51
J 2
(-4060 2910);
DISPLAY 0.680851 (-4060 2910);
PAINT MONO (-4060 2910);
FORCEPROP 0 LASTPIN (-4050 2450) $PN 96
J 2
(-4060 2460);
DISPLAY 0.680851 (-4060 2460);
PAINT MONO (-4060 2460);
FORCEPROP 0 LASTPIN (-4050 2950) $PN 53
J 2
(-4060 2960);
DISPLAY 0.680851 (-4060 2960);
PAINT MONO (-4060 2960);
FORCEPROP 0 LASTPIN (-4050 2500) $PN 98
J 2
(-4060 2510);
DISPLAY 0.680851 (-4060 2510);
PAINT MONO (-4060 2510);
FORCEPROP 0 LASTPIN (-4050 3000) $PN 196
J 2
(-4060 3010);
DISPLAY 0.680851 (-4060 3010);
PAINT MONO (-4060 3010);
FORCEPROP 0 LASTPIN (-4050 2550) $PN 241
J 2
(-4060 2560);
DISPLAY 0.680851 (-4060 2560);
PAINT MONO (-4060 2560);
FORCEPROP 0 LASTPIN (-4050 3050) $PN 198
J 2
(-4060 3060);
DISPLAY 0.680851 (-4060 3060);
PAINT MONO (-4060 3060);
FORCEPROP 0 LASTPIN (-4050 2600) $PN 243
J 2
(-4060 2610);
DISPLAY 0.680851 (-4060 2610);
PAINT MONO (-4060 2610);
FORCEPROP 0 LASTPIN (-4050 3100) $PN 58
J 2
(-4060 3110);
DISPLAY 0.680851 (-4060 3110);
PAINT MONO (-4060 3110);
FORCEPROP 0 LASTPIN (-4050 2650) $PN 89
J 2
(-4060 2660);
DISPLAY 0.680851 (-4060 2660);
PAINT MONO (-4060 2660);
FORCEPROP 0 LASTPIN (-4050 3150) $PN 60
J 2
(-4060 3160);
DISPLAY 0.680851 (-4060 3160);
PAINT MONO (-4060 3160);
FORCEPROP 0 LASTPIN (-4050 2700) $PN 91
J 2
(-4060 2710);
DISPLAY 0.680851 (-4060 2710);
PAINT MONO (-4060 2710);
FORCEPROP 0 LASTPIN (-4050 3200) $PN 203
J 2
(-4060 3210);
DISPLAY 0.680851 (-4060 3210);
PAINT MONO (-4060 3210);
FORCEPROP 0 LASTPIN (-4050 2750) $PN 234
J 2
(-4060 2760);
DISPLAY 0.680851 (-4060 2760);
PAINT MONO (-4060 2760);
FORCEPROP 0 LASTPIN (-4050 3250) $PN 205
J 2
(-4060 3260);
DISPLAY 0.680851 (-4060 3260);
PAINT MONO (-4060 3260);
FORCEPROP 0 LASTPIN (-4050 2800) $PN 236
J 2
(-4060 2810);
DISPLAY 0.680851 (-4060 2810);
PAINT MONO (-4060 2810);
FORCEPROP 0 LASTPIN (-4050 3350) $PN 218
J 2
(-4060 3360);
DISPLAY 0.680851 (-4060 3360);
PAINT MONO (-4060 3360);
FORCEPROP 0 LASTPIN (-4050 3400) $PN 217
J 2
(-4060 3410);
DISPLAY 0.680851 (-4060 3410);
PAINT MONO (-4060 3410);
FORCEPROP 0 LASTPIN (-4050 3650) $PN 64
J 2
(-4060 3660);
DISPLAY 0.680851 (-4060 3660);
PAINT MONO (-4060 3660);
FORCEPROP 0 LASTPIN (-4050 3500) $PN 84
J 2
(-4060 3510);
DISPLAY 0.680851 (-4060 3510);
PAINT MONO (-4060 3510);
FORCEPROP 0 LASTPIN (-4050 3700) $PN 209
J 2
(-4060 3710);
DISPLAY 0.680851 (-4060 3710);
PAINT MONO (-4060 3710);
FORCEPROP 0 LASTPIN (-4050 3550) $PN 229
J 2
(-4060 3560);
DISPLAY 0.680851 (-4060 3560);
PAINT MONO (-4060 3560);
FORCEPROP 0 LASTPIN (-2850 3100) $PN 7
J 0
(-2840 3110);
DISPLAY 0.680851 (-2840 3110);
PAINT MONO (-2840 3110);
FORCEPROP 0 LASTPIN (-2850 1450) $PN 100
J 0
(-2840 1460);
DISPLAY 0.680851 (-2840 1460);
PAINT MONO (-2840 1460);
FORCEPROP 0 LASTPIN (-2850 3150) $PN 9
J 0
(-2840 3160);
DISPLAY 0.680851 (-2840 3160);
PAINT MONO (-2840 3160);
FORCEPROP 0 LASTPIN (-2850 1500) $PN 102
J 0
(-2840 1510);
DISPLAY 0.680851 (-2840 1510);
PAINT MONO (-2840 1510);
FORCEPROP 0 LASTPIN (-2850 3200) $PN 152
J 0
(-2840 3210);
DISPLAY 0.680851 (-2840 3210);
PAINT MONO (-2840 3210);
FORCEPROP 0 LASTPIN (-2850 1550) $PN 245
J 0
(-2840 1560);
DISPLAY 0.680851 (-2840 1560);
PAINT MONO (-2840 1560);
FORCEPROP 0 LASTPIN (-2850 3250) $PN 154
J 0
(-2840 3260);
DISPLAY 0.680851 (-2840 3260);
PAINT MONO (-2840 3260);
FORCEPROP 0 LASTPIN (-2850 1600) $PN 247
J 0
(-2840 1610);
DISPLAY 0.680851 (-2840 1610);
PAINT MONO (-2840 1610);
FORCEPROP 0 LASTPIN (-2850 3300) $PN 14
J 0
(-2840 3310);
DISPLAY 0.680851 (-2840 3310);
PAINT MONO (-2840 3310);
FORCEPROP 0 LASTPIN (-2850 1650) $PN 107
J 0
(-2840 1660);
DISPLAY 0.680851 (-2840 1660);
PAINT MONO (-2840 1660);
FORCEPROP 0 LASTPIN (-2850 3350) $PN 16
J 0
(-2840 3360);
DISPLAY 0.680851 (-2840 3360);
PAINT MONO (-2840 3360);
FORCEPROP 0 LASTPIN (-2850 1700) $PN 109
J 0
(-2840 1710);
DISPLAY 0.680851 (-2840 1710);
PAINT MONO (-2840 1710);
FORCEPROP 0 LASTPIN (-2850 3400) $PN 159
J 0
(-2840 3410);
DISPLAY 0.680851 (-2840 3410);
PAINT MONO (-2840 3410);
FORCEPROP 0 LASTPIN (-2850 1750) $PN 252
J 0
(-2840 1760);
DISPLAY 0.680851 (-2840 1760);
PAINT MONO (-2840 1760);
FORCEPROP 0 LASTPIN (-2850 3450) $PN 161
J 0
(-2840 3460);
DISPLAY 0.680851 (-2840 3460);
PAINT MONO (-2840 3460);
FORCEPROP 0 LASTPIN (-2850 1800) $PN 254
J 0
(-2840 1810);
DISPLAY 0.680851 (-2840 1810);
PAINT MONO (-2840 1810);
FORCEPROP 0 LASTPIN (-2850 3500) $PN 18
J 0
(-2840 3510);
DISPLAY 0.680851 (-2840 3510);
PAINT MONO (-2840 3510);
FORCEPROP 0 LASTPIN (-2850 1850) $PN 111
J 0
(-2840 1860);
DISPLAY 0.680851 (-2840 1860);
PAINT MONO (-2840 1860);
FORCEPROP 0 LASTPIN (-2850 3550) $PN 20
J 0
(-2840 3560);
DISPLAY 0.680851 (-2840 3560);
PAINT MONO (-2840 3560);
FORCEPROP 0 LASTPIN (-2850 1900) $PN 113
J 0
(-2840 1910);
DISPLAY 0.680851 (-2840 1910);
PAINT MONO (-2840 1910);
FORCEPROP 0 LASTPIN (-2850 3600) $PN 163
J 0
(-2840 3610);
DISPLAY 0.680851 (-2840 3610);
PAINT MONO (-2840 3610);
FORCEPROP 0 LASTPIN (-2850 1950) $PN 256
J 0
(-2840 1960);
DISPLAY 0.680851 (-2840 1960);
PAINT MONO (-2840 1960);
FORCEPROP 0 LASTPIN (-2850 3650) $PN 165
J 0
(-2840 3660);
DISPLAY 0.680851 (-2840 3660);
PAINT MONO (-2840 3660);
FORCEPROP 0 LASTPIN (-2850 2000) $PN 258
J 0
(-2840 2010);
DISPLAY 0.680851 (-2840 2010);
PAINT MONO (-2840 2010);
FORCEPROP 0 LASTPIN (-2850 3700) $PN 25
J 0
(-2840 3710);
DISPLAY 0.680851 (-2840 3710);
PAINT MONO (-2840 3710);
FORCEPROP 0 LASTPIN (-2850 2050) $PN 118
J 0
(-2840 2060);
DISPLAY 0.680851 (-2840 2060);
PAINT MONO (-2840 2060);
FORCEPROP 0 LASTPIN (-2850 3750) $PN 27
J 0
(-2840 3760);
DISPLAY 0.680851 (-2840 3760);
PAINT MONO (-2840 3760);
FORCEPROP 0 LASTPIN (-2850 2100) $PN 120
J 0
(-2840 2110);
DISPLAY 0.680851 (-2840 2110);
PAINT MONO (-2840 2110);
FORCEPROP 0 LASTPIN (-2850 3800) $PN 170
J 0
(-2840 3810);
DISPLAY 0.680851 (-2840 3810);
PAINT MONO (-2840 3810);
FORCEPROP 0 LASTPIN (-2850 2150) $PN 263
J 0
(-2840 2160);
DISPLAY 0.680851 (-2840 2160);
PAINT MONO (-2840 2160);
FORCEPROP 0 LASTPIN (-2850 3850) $PN 172
J 0
(-2840 3860);
DISPLAY 0.680851 (-2840 3860);
PAINT MONO (-2840 3860);
FORCEPROP 0 LASTPIN (-2850 2200) $PN 265
J 0
(-2840 2210);
DISPLAY 0.680851 (-2840 2210);
PAINT MONO (-2840 2210);
FORCEPROP 0 LASTPIN (-2850 3900) $PN 29
J 0
(-2840 3910);
DISPLAY 0.680851 (-2840 3910);
PAINT MONO (-2840 3910);
FORCEPROP 0 LASTPIN (-2850 2250) $PN 122
J 0
(-2840 2260);
DISPLAY 0.680851 (-2840 2260);
PAINT MONO (-2840 2260);
FORCEPROP 0 LASTPIN (-2850 3950) $PN 31
J 0
(-2840 3960);
DISPLAY 0.680851 (-2840 3960);
PAINT MONO (-2840 3960);
FORCEPROP 0 LASTPIN (-2850 2300) $PN 124
J 0
(-2840 2310);
DISPLAY 0.680851 (-2840 2310);
PAINT MONO (-2840 2310);
FORCEPROP 0 LASTPIN (-2850 4000) $PN 174
J 0
(-2840 4010);
DISPLAY 0.680851 (-2840 4010);
PAINT MONO (-2840 4010);
FORCEPROP 0 LASTPIN (-2850 2350) $PN 267
J 0
(-2840 2360);
DISPLAY 0.680851 (-2840 2360);
PAINT MONO (-2840 2360);
FORCEPROP 0 LASTPIN (-2850 4050) $PN 176
J 0
(-2840 4060);
DISPLAY 0.680851 (-2840 4060);
PAINT MONO (-2840 4060);
FORCEPROP 0 LASTPIN (-2850 2400) $PN 269
J 0
(-2840 2410);
DISPLAY 0.680851 (-2840 2410);
PAINT MONO (-2840 2410);
FORCEPROP 0 LASTPIN (-2850 4100) $PN 36
J 0
(-2840 4110);
DISPLAY 0.680851 (-2840 4110);
PAINT MONO (-2840 4110);
FORCEPROP 0 LASTPIN (-2850 2450) $PN 129
J 0
(-2840 2460);
DISPLAY 0.680851 (-2840 2460);
PAINT MONO (-2840 2460);
FORCEPROP 0 LASTPIN (-2850 4150) $PN 38
J 0
(-2840 4160);
DISPLAY 0.680851 (-2840 4160);
PAINT MONO (-2840 4160);
FORCEPROP 0 LASTPIN (-2850 2500) $PN 131
J 0
(-2840 2510);
DISPLAY 0.680851 (-2840 2510);
PAINT MONO (-2840 2510);
FORCEPROP 0 LASTPIN (-2850 4200) $PN 181
J 0
(-2840 4210);
DISPLAY 0.680851 (-2840 4210);
PAINT MONO (-2840 4210);
FORCEPROP 0 LASTPIN (-2850 2550) $PN 274
J 0
(-2840 2560);
DISPLAY 0.680851 (-2840 2560);
PAINT MONO (-2840 2560);
FORCEPROP 0 LASTPIN (-2850 4250) $PN 183
J 0
(-2840 4260);
DISPLAY 0.680851 (-2840 4260);
PAINT MONO (-2840 4260);
FORCEPROP 0 LASTPIN (-2850 2600) $PN 276
J 0
(-2840 2610);
DISPLAY 0.680851 (-2840 2610);
PAINT MONO (-2840 2610);
FORCEPROP 0 LASTPIN (-2850 4300) $PN 40
J 0
(-2840 4310);
DISPLAY 0.680851 (-2840 4310);
PAINT MONO (-2840 4310);
FORCEPROP 0 LASTPIN (-2850 2650) $PN 133
J 0
(-2840 2660);
DISPLAY 0.680851 (-2840 2660);
PAINT MONO (-2840 2660);
FORCEPROP 0 LASTPIN (-2850 4350) $PN 42
J 0
(-2840 4360);
DISPLAY 0.680851 (-2840 4360);
PAINT MONO (-2840 4360);
FORCEPROP 0 LASTPIN (-2850 2700) $PN 135
J 0
(-2840 2710);
DISPLAY 0.680851 (-2840 2710);
PAINT MONO (-2840 2710);
FORCEPROP 0 LASTPIN (-2850 4400) $PN 185
J 0
(-2840 4410);
DISPLAY 0.680851 (-2840 4410);
PAINT MONO (-2840 4410);
FORCEPROP 0 LASTPIN (-2850 2750) $PN 278
J 0
(-2840 2760);
DISPLAY 0.680851 (-2840 2760);
PAINT MONO (-2840 2760);
FORCEPROP 0 LASTPIN (-2850 4450) $PN 187
J 0
(-2840 4460);
DISPLAY 0.680851 (-2840 4460);
PAINT MONO (-2840 4460);
FORCEPROP 0 LASTPIN (-2850 2800) $PN 280
J 0
(-2840 2810);
DISPLAY 0.680851 (-2840 2810);
PAINT MONO (-2840 2810);
FORCEPROP 0 LASTPIN (-2850 4500) $PN 47
J 0
(-2840 4510);
DISPLAY 0.680851 (-2840 4510);
PAINT MONO (-2840 4510);
FORCEPROP 0 LASTPIN (-2850 2850) $PN 140
J 0
(-2840 2860);
DISPLAY 0.680851 (-2840 2860);
PAINT MONO (-2840 2860);
FORCEPROP 0 LASTPIN (-2850 4550) $PN 49
J 0
(-2840 4560);
DISPLAY 0.680851 (-2840 4560);
PAINT MONO (-2840 4560);
FORCEPROP 0 LASTPIN (-2850 2900) $PN 142
J 0
(-2840 2910);
DISPLAY 0.680851 (-2840 2910);
PAINT MONO (-2840 2910);
FORCEPROP 0 LASTPIN (-2850 4600) $PN 192
J 0
(-2840 4610);
DISPLAY 0.680851 (-2840 4610);
PAINT MONO (-2840 4610);
FORCEPROP 0 LASTPIN (-2850 2950) $PN 285
J 0
(-2840 2960);
DISPLAY 0.680851 (-2840 2960);
PAINT MONO (-2840 2960);
FORCEPROP 0 LASTPIN (-2850 4650) $PN 194
J 0
(-2840 4660);
DISPLAY 0.680851 (-2840 4660);
PAINT MONO (-2840 4660);
FORCEPROP 0 LASTPIN (-2850 3000) $PN 287
J 0
(-2840 3010);
DISPLAY 0.680851 (-2840 3010);
PAINT MONO (-2840 3010);
FORCEPROP 0 LASTPIN (-4050 2150) $PN 148
J 2
(-4060 2160);
DISPLAY 0.680851 (-4060 2160);
PAINT MONO (-4060 2160);
FORCEPROP 0 LASTPIN (-4050 2050) $PN 4
J 2
(-4060 2060);
DISPLAY 0.680851 (-4060 2060);
PAINT MONO (-4060 2060);
FORCEPROP 0 LASTPIN (-4050 2100) $PN 5
J 2
(-4060 2110);
DISPLAY 0.680851 (-4060 2110);
PAINT MONO (-4060 2110);
FORCEPROP 0 LASTPIN (-4050 1250) $PN 86
J 2
(-4060 1260);
DISPLAY 0.680851 (-4060 1260);
PAINT MONO (-4060 1260);
FORCEPROP 0 LASTPIN (-4050 1200) $PN 87
J 2
(-4060 1210);
DISPLAY 0.680851 (-4060 1210);
PAINT MONO (-4060 1210);
FORCEPROP 0 LASTPIN (-4050 3850) $PN 74
J 2
(-4060 3860);
DISPLAY 0.680851 (-4060 3860);
PAINT MONO (-4060 3860);
FORCEPROP 0 LASTPIN (-4050 3800) $PN 227
J 2
(-4060 3810);
DISPLAY 0.680851 (-4060 3810);
PAINT MONO (-4060 3810);
FORCEPROP 0 LASTPIN (-4050 1800) $PN 147
J 2
(-4060 1810);
DISPLAY 0.680851 (-4060 1810);
PAINT MONO (-4060 1810);
FORCEPROP 0 LASTPIN (-4050 2350) $PN 207
J 2
(-4060 2360);
DISPLAY 0.680851 (-4060 2360);
PAINT MONO (-4060 2360);
FORCEPROP 0 LASTPIN (-4050 1400) $PN 2
J 2
(-4060 1410);
DISPLAY 0.680851 (-4060 1410);
PAINT MONO (-4060 1410);
FORCEPROP 0 LASTPIN (-4050 1450) $PN 144
J 2
(-4060 1460);
DISPLAY 0.680851 (-4060 1460);
PAINT MONO (-4060 1460);
FORCEPROP 0 LASTPIN (-4050 1500) $PN 149
J 2
(-4060 1510);
DISPLAY 0.680851 (-4060 1510);
PAINT MONO (-4060 1510);
FORCEPROP 0 LASTPIN (-4050 1550) $PN 150
J 2
(-4060 1560);
DISPLAY 0.680851 (-4060 1560);
PAINT MONO (-4060 1560);
FORCEPROP 0 LASTPIN (-4050 1600) $PN 220
J 2
(-4060 1610);
DISPLAY 0.680851 (-4060 1610);
PAINT MONO (-4060 1610);
FORCEPROP 0 LASTPIN (-4050 1650) $PN 231
J 2
(-4060 1660);
DISPLAY 0.680851 (-4060 1660);
PAINT MONO (-4060 1660);
FORCEPROP 0 LASTPIN (-4050 1700) $PN 232
J 2
(-4060 1710);
DISPLAY 0.680851 (-4060 1710);
PAINT MONO (-4060 1710);
FORCEPROP 0 LASTPIN (-4050 2200) $PN 3
J 2
(-4060 2210);
DISPLAY 0.680851 (-4060 2210);
PAINT MONO (-4060 2210);
FORCEPROP 1 LAST NEEDS_NO_SIZE TRUE
J 0
(-3450 2925);
DISPLAY 0.723404 (-3450 2925);
PAINT GREEN (-3450 2925);
DISPLAY INVISIBLE (-3450 2925);
FORCEPROP 1 LAST CDS_LMAN_SYM_OUTLINE -450,1875,450,-1875
J 0
(-3450 2925);
DISPLAY 0.468085 (-3450 2925);
PAINT GREEN (-3450 2925);
DISPLAY INVISIBLE (-3450 2925);
FORCEPROP 2 LAST CDS_LIB pure_quanta
J 0
(-3450 2925);
DISPLAY INVISIBLE (-3450 2925);
FORCEPROP 1 LAST PATH I47
J 0
(-3450 2925);
DISPLAY 0.723404 (-3450 2925);
PAINT GREEN (-3450 2925);
DISPLAY INVISIBLE (-3450 2925);
FORCEPROP 2 LAST CDS_LOCATION J20
J 0
(-3900 5150);
DISPLAY 1.021277 (-3900 5150);
DISPLAY INVISIBLE (-3900 5150);
FORCEPROP 0 LAST $SEC 1
J 0
(-3900 5150);
DISPLAY 0.680851 (-3900 5150);
PAINT MONO (-3900 5150);
DISPLAY INVISIBLE (-3900 5150);
FORCEPROP 2 LAST CDS_SEC 1
J 0
(-3900 5150);
DISPLAY 1.021277 (-3900 5150);
DISPLAY INVISIBLE (-3900 5150);
FORCEADD TAP..1
(-2625 1450);
FORCEPROP 3 LASTPIN (-2675 1450) SIG_NAME M_B_CPU1_SB_DQ<0>
J 0
(-2665 1460);
DISPLAY 0.659574 (-2665 1460);
PAINT MONO (-2665 1460);
DISPLAY INVISIBLE (-2665 1460);
FORCEPROP 1 LASTPIN (-2675 1450) BN 0
J 0
(-2687 1458);
DISPLAY 0.680851 (-2687 1458);
PAINT GREEN (-2687 1458);
FORCEPROP 2 LAST CDS_LIB standard
J 0
(-2625 1450);
PAINT MONO (-2625 1450);
DISPLAY INVISIBLE (-2625 1450);
FORCEPROP 1 LAST BODY_TYPE PLUMBING
J 0
(-2625 1500);
DISPLAY 0.872340 (-2625 1500);
PAINT GREEN (-2625 1500);
DISPLAY INVISIBLE (-2625 1500);
FORCEPROP 1 LAST HDL_TAP TRUE
J 0
(-2300 1325);
DISPLAY 0.872340 (-2300 1325);
DISPLAY INVISIBLE (-2300 1325);
FORCEPROP 1 LAST PATH I48
J 0
(-2627 1450);
DISPLAY 0.872340 (-2627 1450);
PAINT GREEN (-2627 1450);
DISPLAY INVISIBLE (-2627 1450);
FORCEADD TAP..1
(-2625 1500);
FORCEPROP 3 LASTPIN (-2675 1500) SIG_NAME M_B_CPU1_SB_DQ<1>
J 0
(-2665 1510);
DISPLAY 0.659574 (-2665 1510);
PAINT MONO (-2665 1510);
DISPLAY INVISIBLE (-2665 1510);
FORCEPROP 1 LASTPIN (-2675 1500) BN 1
J 0
(-2687 1508);
DISPLAY 0.680851 (-2687 1508);
PAINT GREEN (-2687 1508);
FORCEPROP 2 LAST CDS_LIB standard
J 0
(-2625 1500);
PAINT MONO (-2625 1500);
DISPLAY INVISIBLE (-2625 1500);
FORCEPROP 1 LAST BODY_TYPE PLUMBING
J 0
(-2625 1550);
DISPLAY 0.872340 (-2625 1550);
PAINT GREEN (-2625 1550);
DISPLAY INVISIBLE (-2625 1550);
FORCEPROP 1 LAST HDL_TAP TRUE
J 0
(-2300 1375);
DISPLAY 0.872340 (-2300 1375);
DISPLAY INVISIBLE (-2300 1375);
FORCEPROP 1 LAST PATH I49
J 0
(-2627 1500);
DISPLAY 0.872340 (-2627 1500);
PAINT GREEN (-2627 1500);
DISPLAY INVISIBLE (-2627 1500);
FORCEADD TAP..1
(-2625 1550);
FORCEPROP 3 LASTPIN (-2675 1550) SIG_NAME M_B_CPU1_SB_DQ<2>
J 0
(-2665 1560);
DISPLAY 0.659574 (-2665 1560);
PAINT MONO (-2665 1560);
DISPLAY INVISIBLE (-2665 1560);
FORCEPROP 1 LASTPIN (-2675 1550) BN 2
J 0
(-2687 1558);
DISPLAY 0.680851 (-2687 1558);
PAINT GREEN (-2687 1558);
FORCEPROP 2 LAST CDS_LIB standard
J 0
(-2625 1550);
PAINT MONO (-2625 1550);
DISPLAY INVISIBLE (-2625 1550);
FORCEPROP 1 LAST BODY_TYPE PLUMBING
J 0
(-2625 1600);
DISPLAY 0.872340 (-2625 1600);
PAINT GREEN (-2625 1600);
DISPLAY INVISIBLE (-2625 1600);
FORCEPROP 1 LAST HDL_TAP TRUE
J 0
(-2300 1425);
DISPLAY 0.872340 (-2300 1425);
DISPLAY INVISIBLE (-2300 1425);
FORCEPROP 1 LAST PATH I50
J 0
(-2627 1550);
DISPLAY 0.872340 (-2627 1550);
PAINT GREEN (-2627 1550);
DISPLAY INVISIBLE (-2627 1550);
FORCEADD TAP..1
(-2625 1650);
FORCEPROP 3 LASTPIN (-2675 1650) SIG_NAME M_B_CPU1_SB_DQ<4>
J 0
(-2665 1660);
DISPLAY 0.659574 (-2665 1660);
PAINT MONO (-2665 1660);
DISPLAY INVISIBLE (-2665 1660);
FORCEPROP 1 LASTPIN (-2675 1650) BN 4
J 0
(-2687 1658);
DISPLAY 0.680851 (-2687 1658);
PAINT GREEN (-2687 1658);
FORCEPROP 2 LAST CDS_LIB standard
J 0
(-2625 1650);
PAINT MONO (-2625 1650);
DISPLAY INVISIBLE (-2625 1650);
FORCEPROP 1 LAST BODY_TYPE PLUMBING
J 0
(-2625 1700);
DISPLAY 0.872340 (-2625 1700);
PAINT GREEN (-2625 1700);
DISPLAY INVISIBLE (-2625 1700);
FORCEPROP 1 LAST HDL_TAP TRUE
J 0
(-2300 1525);
DISPLAY 0.872340 (-2300 1525);
DISPLAY INVISIBLE (-2300 1525);
FORCEPROP 1 LAST PATH I51
J 0
(-2627 1650);
DISPLAY 0.872340 (-2627 1650);
PAINT GREEN (-2627 1650);
DISPLAY INVISIBLE (-2627 1650);
FORCEADD TAP..1
(-2625 1600);
FORCEPROP 3 LASTPIN (-2675 1600) SIG_NAME M_B_CPU1_SB_DQ<3>
J 0
(-2665 1610);
DISPLAY 0.659574 (-2665 1610);
PAINT MONO (-2665 1610);
DISPLAY INVISIBLE (-2665 1610);
FORCEPROP 1 LASTPIN (-2675 1600) BN 3
J 0
(-2687 1608);
DISPLAY 0.680851 (-2687 1608);
PAINT GREEN (-2687 1608);
FORCEPROP 2 LAST CDS_LIB standard
J 0
(-2625 1600);
PAINT MONO (-2625 1600);
DISPLAY INVISIBLE (-2625 1600);
FORCEPROP 1 LAST BODY_TYPE PLUMBING
J 0
(-2625 1650);
DISPLAY 0.872340 (-2625 1650);
PAINT GREEN (-2625 1650);
DISPLAY INVISIBLE (-2625 1650);
FORCEPROP 1 LAST HDL_TAP TRUE
J 0
(-2300 1475);
DISPLAY 0.872340 (-2300 1475);
DISPLAY INVISIBLE (-2300 1475);
FORCEPROP 1 LAST PATH I52
J 0
(-2627 1600);
DISPLAY 0.872340 (-2627 1600);
PAINT GREEN (-2627 1600);
DISPLAY INVISIBLE (-2627 1600);
FORCEADD TAP..1
(-2625 1750);
FORCEPROP 3 LASTPIN (-2675 1750) SIG_NAME M_B_CPU1_SB_DQ<6>
J 0
(-2665 1760);
DISPLAY 0.659574 (-2665 1760);
PAINT MONO (-2665 1760);
DISPLAY INVISIBLE (-2665 1760);
FORCEPROP 1 LASTPIN (-2675 1750) BN 6
J 0
(-2687 1758);
DISPLAY 0.680851 (-2687 1758);
PAINT GREEN (-2687 1758);
FORCEPROP 2 LAST CDS_LIB standard
J 0
(-2625 1750);
PAINT MONO (-2625 1750);
DISPLAY INVISIBLE (-2625 1750);
FORCEPROP 1 LAST BODY_TYPE PLUMBING
J 0
(-2625 1800);
DISPLAY 0.872340 (-2625 1800);
PAINT GREEN (-2625 1800);
DISPLAY INVISIBLE (-2625 1800);
FORCEPROP 1 LAST HDL_TAP TRUE
J 0
(-2300 1625);
DISPLAY 0.872340 (-2300 1625);
DISPLAY INVISIBLE (-2300 1625);
FORCEPROP 1 LAST PATH I53
J 0
(-2627 1750);
DISPLAY 0.872340 (-2627 1750);
PAINT GREEN (-2627 1750);
DISPLAY INVISIBLE (-2627 1750);
FORCEADD TAP..1
(-2625 1700);
FORCEPROP 3 LASTPIN (-2675 1700) SIG_NAME M_B_CPU1_SB_DQ<5>
J 0
(-2665 1710);
DISPLAY 0.659574 (-2665 1710);
PAINT MONO (-2665 1710);
DISPLAY INVISIBLE (-2665 1710);
FORCEPROP 1 LASTPIN (-2675 1700) BN 5
J 0
(-2687 1708);
DISPLAY 0.680851 (-2687 1708);
PAINT GREEN (-2687 1708);
FORCEPROP 2 LAST CDS_LIB standard
J 0
(-2625 1700);
PAINT MONO (-2625 1700);
DISPLAY INVISIBLE (-2625 1700);
FORCEPROP 1 LAST BODY_TYPE PLUMBING
J 0
(-2625 1750);
DISPLAY 0.872340 (-2625 1750);
PAINT GREEN (-2625 1750);
DISPLAY INVISIBLE (-2625 1750);
FORCEPROP 1 LAST HDL_TAP TRUE
J 0
(-2300 1575);
DISPLAY 0.872340 (-2300 1575);
DISPLAY INVISIBLE (-2300 1575);
FORCEPROP 1 LAST PATH I54
J 0
(-2627 1700);
DISPLAY 0.872340 (-2627 1700);
PAINT GREEN (-2627 1700);
DISPLAY INVISIBLE (-2627 1700);
FORCEADD TAP..1
(-2625 1800);
FORCEPROP 3 LASTPIN (-2675 1800) SIG_NAME M_B_CPU1_SB_DQ<7>
J 0
(-2665 1810);
DISPLAY 0.659574 (-2665 1810);
PAINT MONO (-2665 1810);
DISPLAY INVISIBLE (-2665 1810);
FORCEPROP 1 LASTPIN (-2675 1800) BN 7
J 0
(-2687 1808);
DISPLAY 0.680851 (-2687 1808);
PAINT GREEN (-2687 1808);
FORCEPROP 2 LAST CDS_LIB standard
J 0
(-2625 1800);
PAINT MONO (-2625 1800);
DISPLAY INVISIBLE (-2625 1800);
FORCEPROP 1 LAST BODY_TYPE PLUMBING
J 0
(-2625 1850);
DISPLAY 0.872340 (-2625 1850);
PAINT GREEN (-2625 1850);
DISPLAY INVISIBLE (-2625 1850);
FORCEPROP 1 LAST HDL_TAP TRUE
J 0
(-2300 1675);
DISPLAY 0.872340 (-2300 1675);
DISPLAY INVISIBLE (-2300 1675);
FORCEPROP 1 LAST PATH I55
J 0
(-2627 1800);
DISPLAY 0.872340 (-2627 1800);
PAINT GREEN (-2627 1800);
DISPLAY INVISIBLE (-2627 1800);
FORCEADD TAP..1
(-2625 1850);
FORCEPROP 3 LASTPIN (-2675 1850) SIG_NAME M_B_CPU1_SB_DQ<8>
J 0
(-2665 1860);
DISPLAY 0.659574 (-2665 1860);
PAINT MONO (-2665 1860);
DISPLAY INVISIBLE (-2665 1860);
FORCEPROP 1 LASTPIN (-2675 1850) BN 8
J 0
(-2687 1858);
DISPLAY 0.680851 (-2687 1858);
PAINT GREEN (-2687 1858);
FORCEPROP 2 LAST CDS_LIB standard
J 0
(-2625 1850);
PAINT MONO (-2625 1850);
DISPLAY INVISIBLE (-2625 1850);
FORCEPROP 1 LAST BODY_TYPE PLUMBING
J 0
(-2625 1900);
DISPLAY 0.872340 (-2625 1900);
PAINT GREEN (-2625 1900);
DISPLAY INVISIBLE (-2625 1900);
FORCEPROP 1 LAST HDL_TAP TRUE
J 0
(-2300 1725);
DISPLAY 0.872340 (-2300 1725);
DISPLAY INVISIBLE (-2300 1725);
FORCEPROP 1 LAST PATH I56
J 0
(-2627 1850);
DISPLAY 0.872340 (-2627 1850);
PAINT GREEN (-2627 1850);
DISPLAY INVISIBLE (-2627 1850);
FORCEADD TAP..1
(-2625 1900);
FORCEPROP 3 LASTPIN (-2675 1900) SIG_NAME M_B_CPU1_SB_DQ<9>
J 0
(-2665 1910);
DISPLAY 0.659574 (-2665 1910);
PAINT MONO (-2665 1910);
DISPLAY INVISIBLE (-2665 1910);
FORCEPROP 1 LASTPIN (-2675 1900) BN 9
J 0
(-2687 1908);
DISPLAY 0.680851 (-2687 1908);
PAINT GREEN (-2687 1908);
FORCEPROP 2 LAST CDS_LIB standard
J 0
(-2625 1900);
PAINT MONO (-2625 1900);
DISPLAY INVISIBLE (-2625 1900);
FORCEPROP 1 LAST BODY_TYPE PLUMBING
J 0
(-2625 1950);
DISPLAY 0.872340 (-2625 1950);
PAINT GREEN (-2625 1950);
DISPLAY INVISIBLE (-2625 1950);
FORCEPROP 1 LAST HDL_TAP TRUE
J 0
(-2300 1775);
DISPLAY 0.872340 (-2300 1775);
DISPLAY INVISIBLE (-2300 1775);
FORCEPROP 1 LAST PATH I57
J 0
(-2627 1900);
DISPLAY 0.872340 (-2627 1900);
PAINT GREEN (-2627 1900);
DISPLAY INVISIBLE (-2627 1900);
FORCEADD TAP..1
(-2625 1950);
FORCEPROP 3 LASTPIN (-2675 1950) SIG_NAME M_B_CPU1_SB_DQ<10>
J 0
(-2665 1960);
DISPLAY 0.659574 (-2665 1960);
PAINT MONO (-2665 1960);
DISPLAY INVISIBLE (-2665 1960);
FORCEPROP 1 LASTPIN (-2675 1950) BN 10
J 0
(-2687 1958);
DISPLAY 0.680851 (-2687 1958);
PAINT GREEN (-2687 1958);
FORCEPROP 2 LAST CDS_LIB standard
J 0
(-2625 1950);
PAINT MONO (-2625 1950);
DISPLAY INVISIBLE (-2625 1950);
FORCEPROP 1 LAST BODY_TYPE PLUMBING
J 0
(-2625 2000);
DISPLAY 0.872340 (-2625 2000);
PAINT GREEN (-2625 2000);
DISPLAY INVISIBLE (-2625 2000);
FORCEPROP 1 LAST HDL_TAP TRUE
J 0
(-2300 1825);
DISPLAY 0.872340 (-2300 1825);
DISPLAY INVISIBLE (-2300 1825);
FORCEPROP 1 LAST PATH I58
J 0
(-2627 1950);
DISPLAY 0.872340 (-2627 1950);
PAINT GREEN (-2627 1950);
DISPLAY INVISIBLE (-2627 1950);
FORCEADD TAP..1
(-2625 2000);
FORCEPROP 3 LASTPIN (-2675 2000) SIG_NAME M_B_CPU1_SB_DQ<11>
J 0
(-2665 2010);
DISPLAY 0.659574 (-2665 2010);
PAINT MONO (-2665 2010);
DISPLAY INVISIBLE (-2665 2010);
FORCEPROP 1 LASTPIN (-2675 2000) BN 11
J 0
(-2687 2008);
DISPLAY 0.680851 (-2687 2008);
PAINT GREEN (-2687 2008);
FORCEPROP 2 LAST CDS_LIB standard
J 0
(-2625 2000);
PAINT MONO (-2625 2000);
DISPLAY INVISIBLE (-2625 2000);
FORCEPROP 1 LAST BODY_TYPE PLUMBING
J 0
(-2625 2050);
DISPLAY 0.872340 (-2625 2050);
PAINT GREEN (-2625 2050);
DISPLAY INVISIBLE (-2625 2050);
FORCEPROP 1 LAST HDL_TAP TRUE
J 0
(-2300 1875);
DISPLAY 0.872340 (-2300 1875);
DISPLAY INVISIBLE (-2300 1875);
FORCEPROP 1 LAST PATH I59
J 0
(-2627 2000);
DISPLAY 0.872340 (-2627 2000);
PAINT GREEN (-2627 2000);
DISPLAY INVISIBLE (-2627 2000);
FORCEADD OFFPAGE..1
(-5125 2150);
FORCEPROP 2 LAST $XR0 101 
J 0
(-5617 2150);
DISPLAY 0.638298 (-5617 2150);
PAINT MONO (-5617 2150);
FORCEPROP 2 LAST CDS_LIB standard
J 0
(-5125 2150);
PAINT MONO (-5125 2150);
DISPLAY INVISIBLE (-5125 2150);
FORCEPROP 1 LAST OFFPAGE TRUE
J 0
(-4800 2025);
DISPLAY 0.872340 (-4800 2025);
DISPLAY INVISIBLE (-4800 2025);
FORCEPROP 1 LAST COMMENT_BODY TRUE
J 0
(-5000 2050);
DISPLAY 0.872340 (-5000 2050);
PAINT GREEN (-5000 2050);
DISPLAY INVISIBLE (-5000 2050);
FORCEPROP 2 LAST PATH I6
J 0
(-5075 2225);
DISPLAY 1.021277 (-5075 2225);
DISPLAY INVISIBLE (-5075 2225);
FORCEADD TAP..1
(-2625 2050);
FORCEPROP 3 LASTPIN (-2675 2050) SIG_NAME M_B_CPU1_SB_DQ<12>
J 0
(-2665 2060);
DISPLAY 0.659574 (-2665 2060);
PAINT MONO (-2665 2060);
DISPLAY INVISIBLE (-2665 2060);
FORCEPROP 1 LASTPIN (-2675 2050) BN 12
J 0
(-2687 2058);
DISPLAY 0.680851 (-2687 2058);
PAINT GREEN (-2687 2058);
FORCEPROP 2 LAST CDS_LIB standard
J 0
(-2625 2050);
PAINT MONO (-2625 2050);
DISPLAY INVISIBLE (-2625 2050);
FORCEPROP 1 LAST BODY_TYPE PLUMBING
J 0
(-2625 2100);
DISPLAY 0.872340 (-2625 2100);
PAINT GREEN (-2625 2100);
DISPLAY INVISIBLE (-2625 2100);
FORCEPROP 1 LAST HDL_TAP TRUE
J 0
(-2300 1925);
DISPLAY 0.872340 (-2300 1925);
DISPLAY INVISIBLE (-2300 1925);
FORCEPROP 1 LAST PATH I60
J 0
(-2627 2050);
DISPLAY 0.872340 (-2627 2050);
PAINT GREEN (-2627 2050);
DISPLAY INVISIBLE (-2627 2050);
FORCEADD TAP..1
(-2625 2100);
FORCEPROP 3 LASTPIN (-2675 2100) SIG_NAME M_B_CPU1_SB_DQ<13>
J 0
(-2665 2110);
DISPLAY 0.659574 (-2665 2110);
PAINT MONO (-2665 2110);
DISPLAY INVISIBLE (-2665 2110);
FORCEPROP 1 LASTPIN (-2675 2100) BN 13
J 0
(-2687 2108);
DISPLAY 0.680851 (-2687 2108);
PAINT GREEN (-2687 2108);
FORCEPROP 2 LAST CDS_LIB standard
J 0
(-2625 2100);
PAINT MONO (-2625 2100);
DISPLAY INVISIBLE (-2625 2100);
FORCEPROP 1 LAST BODY_TYPE PLUMBING
J 0
(-2625 2150);
DISPLAY 0.872340 (-2625 2150);
PAINT GREEN (-2625 2150);
DISPLAY INVISIBLE (-2625 2150);
FORCEPROP 1 LAST HDL_TAP TRUE
J 0
(-2300 1975);
DISPLAY 0.872340 (-2300 1975);
DISPLAY INVISIBLE (-2300 1975);
FORCEPROP 1 LAST PATH I61
J 0
(-2627 2100);
DISPLAY 0.872340 (-2627 2100);
PAINT GREEN (-2627 2100);
DISPLAY INVISIBLE (-2627 2100);
FORCEADD TAP..1
(-2625 2150);
FORCEPROP 3 LASTPIN (-2675 2150) SIG_NAME M_B_CPU1_SB_DQ<14>
J 0
(-2665 2160);
DISPLAY 0.659574 (-2665 2160);
PAINT MONO (-2665 2160);
DISPLAY INVISIBLE (-2665 2160);
FORCEPROP 1 LASTPIN (-2675 2150) BN 14
J 0
(-2687 2158);
DISPLAY 0.680851 (-2687 2158);
PAINT GREEN (-2687 2158);
FORCEPROP 2 LAST CDS_LIB standard
J 0
(-2625 2150);
PAINT MONO (-2625 2150);
DISPLAY INVISIBLE (-2625 2150);
FORCEPROP 1 LAST BODY_TYPE PLUMBING
J 0
(-2625 2200);
DISPLAY 0.872340 (-2625 2200);
PAINT GREEN (-2625 2200);
DISPLAY INVISIBLE (-2625 2200);
FORCEPROP 1 LAST HDL_TAP TRUE
J 0
(-2300 2025);
DISPLAY 0.872340 (-2300 2025);
DISPLAY INVISIBLE (-2300 2025);
FORCEPROP 1 LAST PATH I62
J 0
(-2627 2150);
DISPLAY 0.872340 (-2627 2150);
PAINT GREEN (-2627 2150);
DISPLAY INVISIBLE (-2627 2150);
FORCEADD TAP..1
(-2625 2200);
FORCEPROP 3 LASTPIN (-2675 2200) SIG_NAME M_B_CPU1_SB_DQ<15>
J 0
(-2665 2210);
DISPLAY 0.659574 (-2665 2210);
PAINT MONO (-2665 2210);
DISPLAY INVISIBLE (-2665 2210);
FORCEPROP 1 LASTPIN (-2675 2200) BN 15
J 0
(-2687 2208);
DISPLAY 0.680851 (-2687 2208);
PAINT GREEN (-2687 2208);
FORCEPROP 2 LAST CDS_LIB standard
J 0
(-2625 2200);
PAINT MONO (-2625 2200);
DISPLAY INVISIBLE (-2625 2200);
FORCEPROP 1 LAST BODY_TYPE PLUMBING
J 0
(-2625 2250);
DISPLAY 0.872340 (-2625 2250);
PAINT GREEN (-2625 2250);
DISPLAY INVISIBLE (-2625 2250);
FORCEPROP 1 LAST HDL_TAP TRUE
J 0
(-2300 2075);
DISPLAY 0.872340 (-2300 2075);
DISPLAY INVISIBLE (-2300 2075);
FORCEPROP 1 LAST PATH I63
J 0
(-2627 2200);
DISPLAY 0.872340 (-2627 2200);
PAINT GREEN (-2627 2200);
DISPLAY INVISIBLE (-2627 2200);
FORCEADD TAP..1
(-2625 2250);
FORCEPROP 3 LASTPIN (-2675 2250) SIG_NAME M_B_CPU1_SB_DQ<16>
J 0
(-2665 2260);
DISPLAY 0.659574 (-2665 2260);
PAINT MONO (-2665 2260);
DISPLAY INVISIBLE (-2665 2260);
FORCEPROP 1 LASTPIN (-2675 2250) BN 16
J 0
(-2687 2258);
DISPLAY 0.680851 (-2687 2258);
PAINT GREEN (-2687 2258);
FORCEPROP 2 LAST CDS_LIB standard
J 0
(-2625 2250);
PAINT MONO (-2625 2250);
DISPLAY INVISIBLE (-2625 2250);
FORCEPROP 1 LAST BODY_TYPE PLUMBING
J 0
(-2625 2300);
DISPLAY 0.872340 (-2625 2300);
PAINT GREEN (-2625 2300);
DISPLAY INVISIBLE (-2625 2300);
FORCEPROP 1 LAST HDL_TAP TRUE
J 0
(-2300 2125);
DISPLAY 0.872340 (-2300 2125);
DISPLAY INVISIBLE (-2300 2125);
FORCEPROP 1 LAST PATH I64
J 0
(-2627 2250);
DISPLAY 0.872340 (-2627 2250);
PAINT GREEN (-2627 2250);
DISPLAY INVISIBLE (-2627 2250);
FORCEADD TAP..1
(-2625 2300);
FORCEPROP 3 LASTPIN (-2675 2300) SIG_NAME M_B_CPU1_SB_DQ<17>
J 0
(-2665 2310);
DISPLAY 0.659574 (-2665 2310);
PAINT MONO (-2665 2310);
DISPLAY INVISIBLE (-2665 2310);
FORCEPROP 1 LASTPIN (-2675 2300) BN 17
J 0
(-2687 2308);
DISPLAY 0.680851 (-2687 2308);
PAINT GREEN (-2687 2308);
FORCEPROP 2 LAST CDS_LIB standard
J 0
(-2625 2300);
PAINT MONO (-2625 2300);
DISPLAY INVISIBLE (-2625 2300);
FORCEPROP 1 LAST BODY_TYPE PLUMBING
J 0
(-2625 2350);
DISPLAY 0.872340 (-2625 2350);
PAINT GREEN (-2625 2350);
DISPLAY INVISIBLE (-2625 2350);
FORCEPROP 1 LAST HDL_TAP TRUE
J 0
(-2300 2175);
DISPLAY 0.872340 (-2300 2175);
DISPLAY INVISIBLE (-2300 2175);
FORCEPROP 1 LAST PATH I65
J 0
(-2627 2300);
DISPLAY 0.872340 (-2627 2300);
PAINT GREEN (-2627 2300);
DISPLAY INVISIBLE (-2627 2300);
FORCEADD TAP..1
(-2625 2350);
FORCEPROP 3 LASTPIN (-2675 2350) SIG_NAME M_B_CPU1_SB_DQ<18>
J 0
(-2665 2360);
DISPLAY 0.659574 (-2665 2360);
PAINT MONO (-2665 2360);
DISPLAY INVISIBLE (-2665 2360);
FORCEPROP 1 LASTPIN (-2675 2350) BN 18
J 0
(-2687 2358);
DISPLAY 0.680851 (-2687 2358);
PAINT GREEN (-2687 2358);
FORCEPROP 2 LAST CDS_LIB standard
J 0
(-2625 2350);
PAINT MONO (-2625 2350);
DISPLAY INVISIBLE (-2625 2350);
FORCEPROP 1 LAST BODY_TYPE PLUMBING
J 0
(-2625 2400);
DISPLAY 0.872340 (-2625 2400);
PAINT GREEN (-2625 2400);
DISPLAY INVISIBLE (-2625 2400);
FORCEPROP 1 LAST HDL_TAP TRUE
J 0
(-2300 2225);
DISPLAY 0.872340 (-2300 2225);
DISPLAY INVISIBLE (-2300 2225);
FORCEPROP 1 LAST PATH I66
J 0
(-2627 2350);
DISPLAY 0.872340 (-2627 2350);
PAINT GREEN (-2627 2350);
DISPLAY INVISIBLE (-2627 2350);
FORCEADD TAP..1
(-2625 2400);
FORCEPROP 3 LASTPIN (-2675 2400) SIG_NAME M_B_CPU1_SB_DQ<19>
J 0
(-2665 2410);
DISPLAY 0.659574 (-2665 2410);
PAINT MONO (-2665 2410);
DISPLAY INVISIBLE (-2665 2410);
FORCEPROP 1 LASTPIN (-2675 2400) BN 19
J 0
(-2687 2408);
DISPLAY 0.680851 (-2687 2408);
PAINT GREEN (-2687 2408);
FORCEPROP 2 LAST CDS_LIB standard
J 0
(-2625 2400);
PAINT MONO (-2625 2400);
DISPLAY INVISIBLE (-2625 2400);
FORCEPROP 1 LAST BODY_TYPE PLUMBING
J 0
(-2625 2450);
DISPLAY 0.872340 (-2625 2450);
PAINT GREEN (-2625 2450);
DISPLAY INVISIBLE (-2625 2450);
FORCEPROP 1 LAST HDL_TAP TRUE
J 0
(-2300 2275);
DISPLAY 0.872340 (-2300 2275);
DISPLAY INVISIBLE (-2300 2275);
FORCEPROP 1 LAST PATH I67
J 0
(-2627 2400);
DISPLAY 0.872340 (-2627 2400);
PAINT GREEN (-2627 2400);
DISPLAY INVISIBLE (-2627 2400);
FORCEADD TAP..1
(-2625 2450);
FORCEPROP 3 LASTPIN (-2675 2450) SIG_NAME M_B_CPU1_SB_DQ<20>
J 0
(-2665 2460);
DISPLAY 0.659574 (-2665 2460);
PAINT MONO (-2665 2460);
DISPLAY INVISIBLE (-2665 2460);
FORCEPROP 1 LASTPIN (-2675 2450) BN 20
J 0
(-2687 2458);
DISPLAY 0.680851 (-2687 2458);
PAINT GREEN (-2687 2458);
FORCEPROP 2 LAST CDS_LIB standard
J 0
(-2625 2450);
PAINT MONO (-2625 2450);
DISPLAY INVISIBLE (-2625 2450);
FORCEPROP 1 LAST BODY_TYPE PLUMBING
J 0
(-2625 2500);
DISPLAY 0.872340 (-2625 2500);
PAINT GREEN (-2625 2500);
DISPLAY INVISIBLE (-2625 2500);
FORCEPROP 1 LAST HDL_TAP TRUE
J 0
(-2300 2325);
DISPLAY 0.872340 (-2300 2325);
DISPLAY INVISIBLE (-2300 2325);
FORCEPROP 1 LAST PATH I68
J 0
(-2627 2450);
DISPLAY 0.872340 (-2627 2450);
PAINT GREEN (-2627 2450);
DISPLAY INVISIBLE (-2627 2450);
FORCEADD TAP..1
(-2625 2550);
FORCEPROP 3 LASTPIN (-2675 2550) SIG_NAME M_B_CPU1_SB_DQ<22>
J 0
(-2665 2560);
DISPLAY 0.659574 (-2665 2560);
PAINT MONO (-2665 2560);
DISPLAY INVISIBLE (-2665 2560);
FORCEPROP 1 LASTPIN (-2675 2550) BN 22
J 0
(-2687 2558);
DISPLAY 0.680851 (-2687 2558);
PAINT GREEN (-2687 2558);
FORCEPROP 2 LAST CDS_LIB standard
J 0
(-2625 2550);
DISPLAY INVISIBLE (-2625 2550);
FORCEPROP 1 LAST BODY_TYPE PLUMBING
J 0
(-2625 2600);
DISPLAY 0.872340 (-2625 2600);
PAINT GREEN (-2625 2600);
DISPLAY INVISIBLE (-2625 2600);
FORCEPROP 1 LAST HDL_TAP TRUE
J 0
(-2300 2425);
DISPLAY 0.872340 (-2300 2425);
DISPLAY INVISIBLE (-2300 2425);
FORCEPROP 1 LAST PATH I69
J 0
(-2627 2550);
DISPLAY 0.872340 (-2627 2550);
PAINT GREEN (-2627 2550);
DISPLAY INVISIBLE (-2627 2550);
FORCEADD OFFPAGE..1
(-5125 2100);
FORCEPROP 2 LAST $XR7 105 
J 0
(-5527 2136);
DISPLAY 0.638298 (-5527 2136);
PAINT MONO (-5527 2136);
FORCEPROP 2 LAST $XR6 104 
J 0
(-5407 2136);
DISPLAY 0.638298 (-5407 2136);
PAINT MONO (-5407 2136);
FORCEPROP 2 LAST $XR5 103 
J 0
(-5647 2064);
DISPLAY 0.638298 (-5647 2064);
PAINT MONO (-5647 2064);
FORCEPROP 2 LAST $XR4 102 
J 0
(-5527 2064);
DISPLAY 0.638298 (-5527 2064);
PAINT MONO (-5527 2064);
FORCEPROP 2 LAST $XR3 100 
J 0
(-5407 2064);
DISPLAY 0.638298 (-5407 2064);
PAINT MONO (-5407 2064);
FORCEPROP 2 LAST $XR2 99 
J 0
(-5587 2100);
DISPLAY 0.638298 (-5587 2100);
PAINT MONO (-5587 2100);
FORCEPROP 2 LAST $XR1 98 
J 0
(-5497 2100);
DISPLAY 0.638298 (-5497 2100);
PAINT MONO (-5497 2100);
FORCEPROP 2 LAST $XR0 230 
J 0
(-5407 2100);
DISPLAY 0.638298 (-5407 2100);
PAINT MONO (-5407 2100);
FORCEPROP 2 LAST CDS_LIB standard
J 0
(-5125 2100);
PAINT MONO (-5125 2100);
DISPLAY INVISIBLE (-5125 2100);
FORCEPROP 1 LAST OFFPAGE TRUE
J 0
(-4800 1975);
DISPLAY 0.872340 (-4800 1975);
DISPLAY INVISIBLE (-4800 1975);
FORCEPROP 1 LAST COMMENT_BODY TRUE
J 0
(-5000 2000);
DISPLAY 0.872340 (-5000 2000);
PAINT GREEN (-5000 2000);
DISPLAY INVISIBLE (-5000 2000);
FORCEPROP 2 LAST PATH I7
J 0
(-5075 2175);
DISPLAY 1.021277 (-5075 2175);
DISPLAY INVISIBLE (-5075 2175);
FORCEADD TAP..1
(-2625 2500);
FORCEPROP 3 LASTPIN (-2675 2500) SIG_NAME M_B_CPU1_SB_DQ<21>
J 0
(-2665 2510);
DISPLAY 0.659574 (-2665 2510);
PAINT MONO (-2665 2510);
DISPLAY INVISIBLE (-2665 2510);
FORCEPROP 1 LASTPIN (-2675 2500) BN 21
J 0
(-2687 2508);
DISPLAY 0.680851 (-2687 2508);
PAINT GREEN (-2687 2508);
FORCEPROP 2 LAST CDS_LIB standard
J 0
(-2625 2500);
PAINT MONO (-2625 2500);
DISPLAY INVISIBLE (-2625 2500);
FORCEPROP 1 LAST BODY_TYPE PLUMBING
J 0
(-2625 2550);
DISPLAY 0.872340 (-2625 2550);
PAINT GREEN (-2625 2550);
DISPLAY INVISIBLE (-2625 2550);
FORCEPROP 1 LAST HDL_TAP TRUE
J 0
(-2300 2375);
DISPLAY 0.872340 (-2300 2375);
DISPLAY INVISIBLE (-2300 2375);
FORCEPROP 1 LAST PATH I70
J 0
(-2627 2500);
DISPLAY 0.872340 (-2627 2500);
PAINT GREEN (-2627 2500);
DISPLAY INVISIBLE (-2627 2500);
FORCEADD TAP..1
(-2625 2600);
FORCEPROP 3 LASTPIN (-2675 2600) SIG_NAME M_B_CPU1_SB_DQ<23>
J 0
(-2665 2610);
DISPLAY 0.659574 (-2665 2610);
PAINT MONO (-2665 2610);
DISPLAY INVISIBLE (-2665 2610);
FORCEPROP 1 LASTPIN (-2675 2600) BN 23
J 0
(-2687 2608);
DISPLAY 0.680851 (-2687 2608);
PAINT GREEN (-2687 2608);
FORCEPROP 2 LAST CDS_LIB standard
J 0
(-2625 2600);
DISPLAY INVISIBLE (-2625 2600);
FORCEPROP 1 LAST BODY_TYPE PLUMBING
J 0
(-2625 2650);
DISPLAY 0.872340 (-2625 2650);
PAINT GREEN (-2625 2650);
DISPLAY INVISIBLE (-2625 2650);
FORCEPROP 1 LAST HDL_TAP TRUE
J 0
(-2300 2475);
DISPLAY 0.872340 (-2300 2475);
DISPLAY INVISIBLE (-2300 2475);
FORCEPROP 1 LAST PATH I71
J 0
(-2627 2600);
DISPLAY 0.872340 (-2627 2600);
PAINT GREEN (-2627 2600);
DISPLAY INVISIBLE (-2627 2600);
FORCEADD TAP..1
(-2625 2650);
FORCEPROP 3 LASTPIN (-2675 2650) SIG_NAME M_B_CPU1_SB_DQ<24>
J 0
(-2665 2660);
DISPLAY 0.659574 (-2665 2660);
PAINT MONO (-2665 2660);
DISPLAY INVISIBLE (-2665 2660);
FORCEPROP 1 LASTPIN (-2675 2650) BN 24
J 0
(-2687 2658);
DISPLAY 0.680851 (-2687 2658);
PAINT GREEN (-2687 2658);
FORCEPROP 2 LAST CDS_LIB standard
J 0
(-2625 2650);
DISPLAY INVISIBLE (-2625 2650);
FORCEPROP 1 LAST BODY_TYPE PLUMBING
J 0
(-2625 2700);
DISPLAY 0.872340 (-2625 2700);
PAINT GREEN (-2625 2700);
DISPLAY INVISIBLE (-2625 2700);
FORCEPROP 1 LAST HDL_TAP TRUE
J 0
(-2300 2525);
DISPLAY 0.872340 (-2300 2525);
DISPLAY INVISIBLE (-2300 2525);
FORCEPROP 1 LAST PATH I72
J 0
(-2627 2650);
DISPLAY 0.872340 (-2627 2650);
PAINT GREEN (-2627 2650);
DISPLAY INVISIBLE (-2627 2650);
FORCEADD TAP..1
(-2625 2700);
FORCEPROP 3 LASTPIN (-2675 2700) SIG_NAME M_B_CPU1_SB_DQ<25>
J 0
(-2665 2710);
DISPLAY 0.659574 (-2665 2710);
PAINT MONO (-2665 2710);
DISPLAY INVISIBLE (-2665 2710);
FORCEPROP 1 LASTPIN (-2675 2700) BN 25
J 0
(-2687 2708);
DISPLAY 0.680851 (-2687 2708);
PAINT GREEN (-2687 2708);
FORCEPROP 2 LAST CDS_LIB standard
J 0
(-2625 2700);
DISPLAY INVISIBLE (-2625 2700);
FORCEPROP 1 LAST BODY_TYPE PLUMBING
J 0
(-2625 2750);
DISPLAY 0.872340 (-2625 2750);
PAINT GREEN (-2625 2750);
DISPLAY INVISIBLE (-2625 2750);
FORCEPROP 1 LAST HDL_TAP TRUE
J 0
(-2300 2575);
DISPLAY 0.872340 (-2300 2575);
DISPLAY INVISIBLE (-2300 2575);
FORCEPROP 1 LAST PATH I73
J 0
(-2627 2700);
DISPLAY 0.872340 (-2627 2700);
PAINT GREEN (-2627 2700);
DISPLAY INVISIBLE (-2627 2700);
FORCEADD TAP..1
(-2625 2800);
FORCEPROP 3 LASTPIN (-2675 2800) SIG_NAME M_B_CPU1_SB_DQ<27>
J 0
(-2665 2810);
DISPLAY 0.659574 (-2665 2810);
PAINT MONO (-2665 2810);
DISPLAY INVISIBLE (-2665 2810);
FORCEPROP 1 LASTPIN (-2675 2800) BN 27
J 0
(-2687 2808);
DISPLAY 0.680851 (-2687 2808);
PAINT GREEN (-2687 2808);
FORCEPROP 2 LAST CDS_LIB standard
J 0
(-2625 2800);
DISPLAY INVISIBLE (-2625 2800);
FORCEPROP 1 LAST BODY_TYPE PLUMBING
J 0
(-2625 2850);
DISPLAY 0.872340 (-2625 2850);
PAINT GREEN (-2625 2850);
DISPLAY INVISIBLE (-2625 2850);
FORCEPROP 1 LAST HDL_TAP TRUE
J 0
(-2300 2675);
DISPLAY 0.872340 (-2300 2675);
DISPLAY INVISIBLE (-2300 2675);
FORCEPROP 1 LAST PATH I74
J 0
(-2627 2800);
DISPLAY 0.872340 (-2627 2800);
PAINT GREEN (-2627 2800);
DISPLAY INVISIBLE (-2627 2800);
FORCEADD TAP..1
(-2625 2750);
FORCEPROP 3 LASTPIN (-2675 2750) SIG_NAME M_B_CPU1_SB_DQ<26>
J 0
(-2665 2760);
DISPLAY 0.659574 (-2665 2760);
PAINT MONO (-2665 2760);
DISPLAY INVISIBLE (-2665 2760);
FORCEPROP 1 LASTPIN (-2675 2750) BN 26
J 0
(-2687 2758);
DISPLAY 0.680851 (-2687 2758);
PAINT GREEN (-2687 2758);
FORCEPROP 2 LAST CDS_LIB standard
J 0
(-2625 2750);
DISPLAY INVISIBLE (-2625 2750);
FORCEPROP 1 LAST BODY_TYPE PLUMBING
J 0
(-2625 2800);
DISPLAY 0.872340 (-2625 2800);
PAINT GREEN (-2625 2800);
DISPLAY INVISIBLE (-2625 2800);
FORCEPROP 1 LAST HDL_TAP TRUE
J 0
(-2300 2625);
DISPLAY 0.872340 (-2300 2625);
DISPLAY INVISIBLE (-2300 2625);
FORCEPROP 1 LAST PATH I75
J 0
(-2627 2750);
DISPLAY 0.872340 (-2627 2750);
PAINT GREEN (-2627 2750);
DISPLAY INVISIBLE (-2627 2750);
FORCEADD TAP..1
(-2625 2850);
FORCEPROP 3 LASTPIN (-2675 2850) SIG_NAME M_B_CPU1_SB_DQ<28>
J 0
(-2665 2860);
DISPLAY 0.659574 (-2665 2860);
PAINT MONO (-2665 2860);
DISPLAY INVISIBLE (-2665 2860);
FORCEPROP 1 LASTPIN (-2675 2850) BN 28
J 0
(-2687 2858);
DISPLAY 0.680851 (-2687 2858);
PAINT GREEN (-2687 2858);
FORCEPROP 2 LAST CDS_LIB standard
J 0
(-2625 2850);
DISPLAY INVISIBLE (-2625 2850);
FORCEPROP 1 LAST BODY_TYPE PLUMBING
J 0
(-2625 2900);
DISPLAY 0.872340 (-2625 2900);
PAINT GREEN (-2625 2900);
DISPLAY INVISIBLE (-2625 2900);
FORCEPROP 1 LAST HDL_TAP TRUE
J 0
(-2300 2725);
DISPLAY 0.872340 (-2300 2725);
DISPLAY INVISIBLE (-2300 2725);
FORCEPROP 1 LAST PATH I76
J 0
(-2627 2850);
DISPLAY 0.872340 (-2627 2850);
PAINT GREEN (-2627 2850);
DISPLAY INVISIBLE (-2627 2850);
FORCEADD TAP..1
(-2625 2900);
FORCEPROP 3 LASTPIN (-2675 2900) SIG_NAME M_B_CPU1_SB_DQ<29>
J 0
(-2665 2910);
DISPLAY 0.659574 (-2665 2910);
PAINT MONO (-2665 2910);
DISPLAY INVISIBLE (-2665 2910);
FORCEPROP 1 LASTPIN (-2675 2900) BN 29
J 0
(-2687 2908);
DISPLAY 0.680851 (-2687 2908);
PAINT GREEN (-2687 2908);
FORCEPROP 2 LAST CDS_LIB standard
J 0
(-2625 2900);
DISPLAY INVISIBLE (-2625 2900);
FORCEPROP 1 LAST BODY_TYPE PLUMBING
J 0
(-2625 2950);
DISPLAY 0.872340 (-2625 2950);
PAINT GREEN (-2625 2950);
DISPLAY INVISIBLE (-2625 2950);
FORCEPROP 1 LAST HDL_TAP TRUE
J 0
(-2300 2775);
DISPLAY 0.872340 (-2300 2775);
DISPLAY INVISIBLE (-2300 2775);
FORCEPROP 1 LAST PATH I77
J 0
(-2627 2900);
DISPLAY 0.872340 (-2627 2900);
PAINT GREEN (-2627 2900);
DISPLAY INVISIBLE (-2627 2900);
FORCEADD TAP..1
(-2625 3000);
FORCEPROP 3 LASTPIN (-2675 3000) SIG_NAME M_B_CPU1_SB_DQ<31>
J 0
(-2665 3010);
DISPLAY 0.659574 (-2665 3010);
PAINT MONO (-2665 3010);
DISPLAY INVISIBLE (-2665 3010);
FORCEPROP 1 LASTPIN (-2675 3000) BN 31
J 0
(-2687 3008);
DISPLAY 0.680851 (-2687 3008);
PAINT GREEN (-2687 3008);
FORCEPROP 2 LAST CDS_LIB standard
J 0
(-2625 3000);
DISPLAY INVISIBLE (-2625 3000);
FORCEPROP 1 LAST BODY_TYPE PLUMBING
J 0
(-2625 3050);
DISPLAY 0.872340 (-2625 3050);
PAINT GREEN (-2625 3050);
DISPLAY INVISIBLE (-2625 3050);
FORCEPROP 1 LAST HDL_TAP TRUE
J 0
(-2300 2875);
DISPLAY 0.872340 (-2300 2875);
DISPLAY INVISIBLE (-2300 2875);
FORCEPROP 1 LAST PATH I78
J 0
(-2627 3000);
DISPLAY 0.872340 (-2627 3000);
PAINT GREEN (-2627 3000);
DISPLAY INVISIBLE (-2627 3000);
FORCEADD TAP..1
(-2625 2950);
FORCEPROP 3 LASTPIN (-2675 2950) SIG_NAME M_B_CPU1_SB_DQ<30>
J 0
(-2665 2960);
DISPLAY 0.659574 (-2665 2960);
PAINT MONO (-2665 2960);
DISPLAY INVISIBLE (-2665 2960);
FORCEPROP 1 LASTPIN (-2675 2950) BN 30
J 0
(-2687 2958);
DISPLAY 0.680851 (-2687 2958);
PAINT GREEN (-2687 2958);
FORCEPROP 2 LAST CDS_LIB standard
J 0
(-2625 2950);
DISPLAY INVISIBLE (-2625 2950);
FORCEPROP 1 LAST BODY_TYPE PLUMBING
J 0
(-2625 3000);
DISPLAY 0.872340 (-2625 3000);
PAINT GREEN (-2625 3000);
DISPLAY INVISIBLE (-2625 3000);
FORCEPROP 1 LAST HDL_TAP TRUE
J 0
(-2300 2825);
DISPLAY 0.872340 (-2300 2825);
DISPLAY INVISIBLE (-2300 2825);
FORCEPROP 1 LAST PATH I79
J 0
(-2627 2950);
DISPLAY 0.872340 (-2627 2950);
PAINT GREEN (-2627 2950);
DISPLAY INVISIBLE (-2627 2950);
FORCEADD OFFPAGE..1
(-5200 2300);
FORCEPROP 2 LAST $XR1 100 
J 0
(-5541 2300);
DISPLAY 0.638298 (-5541 2300);
PAINT MONO (-5541 2300);
FORCEPROP 2 LAST $XR0 52 
J 0
(-5421 2300);
DISPLAY 0.638298 (-5421 2300);
PAINT MONO (-5421 2300);
FORCEPROP 2 LAST CDS_LIB standard
J 0
(-5200 2300);
PAINT MONO (-5200 2300);
DISPLAY INVISIBLE (-5200 2300);
FORCEPROP 1 LAST OFFPAGE TRUE
J 0
(-4875 2175);
DISPLAY 0.872340 (-4875 2175);
DISPLAY INVISIBLE (-4875 2175);
FORCEPROP 1 LAST COMMENT_BODY TRUE
J 0
(-5075 2200);
DISPLAY 0.872340 (-5075 2200);
PAINT GREEN (-5075 2200);
DISPLAY INVISIBLE (-5075 2200);
FORCEPROP 2 LAST PATH I8
J 0
(-5150 2375);
DISPLAY 1.021277 (-5150 2375);
DISPLAY INVISIBLE (-5150 2375);
FORCEADD TAP..1
(-2625 3150);
FORCEPROP 3 LASTPIN (-2675 3150) SIG_NAME M_B_CPU1_SA_DQ<1>
J 0
(-2665 3160);
DISPLAY 0.659574 (-2665 3160);
PAINT MONO (-2665 3160);
DISPLAY INVISIBLE (-2665 3160);
FORCEPROP 1 LASTPIN (-2675 3150) BN 1
J 0
(-2687 3158);
DISPLAY 0.680851 (-2687 3158);
PAINT GREEN (-2687 3158);
FORCEPROP 2 LAST CDS_LIB standard
J 0
(-2625 3150);
PAINT MONO (-2625 3150);
DISPLAY INVISIBLE (-2625 3150);
FORCEPROP 1 LAST BODY_TYPE PLUMBING
J 0
(-2625 3200);
DISPLAY 0.872340 (-2625 3200);
PAINT GREEN (-2625 3200);
DISPLAY INVISIBLE (-2625 3200);
FORCEPROP 1 LAST HDL_TAP TRUE
J 0
(-2300 3025);
DISPLAY 0.872340 (-2300 3025);
DISPLAY INVISIBLE (-2300 3025);
FORCEPROP 1 LAST PATH I80
J 0
(-2627 3150);
DISPLAY 0.872340 (-2627 3150);
PAINT GREEN (-2627 3150);
DISPLAY INVISIBLE (-2627 3150);
FORCEADD TAP..1
(-2625 3100);
FORCEPROP 3 LASTPIN (-2675 3100) SIG_NAME M_B_CPU1_SA_DQ<0>
J 0
(-2665 3110);
DISPLAY 0.659574 (-2665 3110);
PAINT MONO (-2665 3110);
DISPLAY INVISIBLE (-2665 3110);
FORCEPROP 1 LASTPIN (-2675 3100) BN 0
J 0
(-2687 3108);
DISPLAY 0.680851 (-2687 3108);
PAINT GREEN (-2687 3108);
FORCEPROP 2 LAST CDS_LIB standard
J 0
(-2625 3100);
PAINT MONO (-2625 3100);
DISPLAY INVISIBLE (-2625 3100);
FORCEPROP 1 LAST BODY_TYPE PLUMBING
J 0
(-2625 3150);
DISPLAY 0.872340 (-2625 3150);
PAINT GREEN (-2625 3150);
DISPLAY INVISIBLE (-2625 3150);
FORCEPROP 1 LAST HDL_TAP TRUE
J 0
(-2300 2975);
DISPLAY 0.872340 (-2300 2975);
DISPLAY INVISIBLE (-2300 2975);
FORCEPROP 1 LAST PATH I81
J 0
(-2627 3100);
DISPLAY 0.872340 (-2627 3100);
PAINT GREEN (-2627 3100);
DISPLAY INVISIBLE (-2627 3100);
FORCEADD TAP..1
(-2625 3250);
FORCEPROP 3 LASTPIN (-2675 3250) SIG_NAME M_B_CPU1_SA_DQ<3>
J 0
(-2665 3260);
DISPLAY 0.659574 (-2665 3260);
PAINT MONO (-2665 3260);
DISPLAY INVISIBLE (-2665 3260);
FORCEPROP 1 LASTPIN (-2675 3250) BN 3
J 0
(-2687 3258);
DISPLAY 0.680851 (-2687 3258);
PAINT GREEN (-2687 3258);
FORCEPROP 2 LAST CDS_LIB standard
J 0
(-2625 3250);
PAINT MONO (-2625 3250);
DISPLAY INVISIBLE (-2625 3250);
FORCEPROP 1 LAST BODY_TYPE PLUMBING
J 0
(-2625 3300);
DISPLAY 0.872340 (-2625 3300);
PAINT GREEN (-2625 3300);
DISPLAY INVISIBLE (-2625 3300);
FORCEPROP 1 LAST HDL_TAP TRUE
J 0
(-2300 3125);
DISPLAY 0.872340 (-2300 3125);
DISPLAY INVISIBLE (-2300 3125);
FORCEPROP 1 LAST PATH I82
J 0
(-2627 3250);
DISPLAY 0.872340 (-2627 3250);
PAINT GREEN (-2627 3250);
DISPLAY INVISIBLE (-2627 3250);
FORCEADD TAP..1
(-2625 3200);
FORCEPROP 3 LASTPIN (-2675 3200) SIG_NAME M_B_CPU1_SA_DQ<2>
J 0
(-2665 3210);
DISPLAY 0.659574 (-2665 3210);
PAINT MONO (-2665 3210);
DISPLAY INVISIBLE (-2665 3210);
FORCEPROP 1 LASTPIN (-2675 3200) BN 2
J 0
(-2687 3208);
DISPLAY 0.680851 (-2687 3208);
PAINT GREEN (-2687 3208);
FORCEPROP 2 LAST CDS_LIB standard
J 0
(-2625 3200);
PAINT MONO (-2625 3200);
DISPLAY INVISIBLE (-2625 3200);
FORCEPROP 1 LAST BODY_TYPE PLUMBING
J 0
(-2625 3250);
DISPLAY 0.872340 (-2625 3250);
PAINT GREEN (-2625 3250);
DISPLAY INVISIBLE (-2625 3250);
FORCEPROP 1 LAST HDL_TAP TRUE
J 0
(-2300 3075);
DISPLAY 0.872340 (-2300 3075);
DISPLAY INVISIBLE (-2300 3075);
FORCEPROP 1 LAST PATH I83
J 0
(-2627 3200);
DISPLAY 0.872340 (-2627 3200);
PAINT GREEN (-2627 3200);
DISPLAY INVISIBLE (-2627 3200);
FORCEADD TAP..1
(-2625 3300);
FORCEPROP 3 LASTPIN (-2675 3300) SIG_NAME M_B_CPU1_SA_DQ<4>
J 0
(-2665 3310);
DISPLAY 0.659574 (-2665 3310);
PAINT MONO (-2665 3310);
DISPLAY INVISIBLE (-2665 3310);
FORCEPROP 1 LASTPIN (-2675 3300) BN 4
J 0
(-2687 3308);
DISPLAY 0.680851 (-2687 3308);
PAINT GREEN (-2687 3308);
FORCEPROP 2 LAST CDS_LIB standard
J 0
(-2625 3300);
PAINT MONO (-2625 3300);
DISPLAY INVISIBLE (-2625 3300);
FORCEPROP 1 LAST BODY_TYPE PLUMBING
J 0
(-2625 3350);
DISPLAY 0.872340 (-2625 3350);
PAINT GREEN (-2625 3350);
DISPLAY INVISIBLE (-2625 3350);
FORCEPROP 1 LAST HDL_TAP TRUE
J 0
(-2300 3175);
DISPLAY 0.872340 (-2300 3175);
DISPLAY INVISIBLE (-2300 3175);
FORCEPROP 1 LAST PATH I84
J 0
(-2627 3300);
DISPLAY 0.872340 (-2627 3300);
PAINT GREEN (-2627 3300);
DISPLAY INVISIBLE (-2627 3300);
FORCEADD TAP..1
(-2625 3400);
FORCEPROP 3 LASTPIN (-2675 3400) SIG_NAME M_B_CPU1_SA_DQ<6>
J 0
(-2665 3410);
DISPLAY 0.659574 (-2665 3410);
PAINT MONO (-2665 3410);
DISPLAY INVISIBLE (-2665 3410);
FORCEPROP 1 LASTPIN (-2675 3400) BN 6
J 0
(-2687 3408);
DISPLAY 0.680851 (-2687 3408);
PAINT GREEN (-2687 3408);
FORCEPROP 2 LAST CDS_LIB standard
J 0
(-2625 3400);
PAINT MONO (-2625 3400);
DISPLAY INVISIBLE (-2625 3400);
FORCEPROP 1 LAST BODY_TYPE PLUMBING
J 0
(-2625 3450);
DISPLAY 0.872340 (-2625 3450);
PAINT GREEN (-2625 3450);
DISPLAY INVISIBLE (-2625 3450);
FORCEPROP 1 LAST HDL_TAP TRUE
J 0
(-2300 3275);
DISPLAY 0.872340 (-2300 3275);
DISPLAY INVISIBLE (-2300 3275);
FORCEPROP 1 LAST PATH I85
J 0
(-2627 3400);
DISPLAY 0.872340 (-2627 3400);
PAINT GREEN (-2627 3400);
DISPLAY INVISIBLE (-2627 3400);
FORCEADD TAP..1
(-2625 3350);
FORCEPROP 3 LASTPIN (-2675 3350) SIG_NAME M_B_CPU1_SA_DQ<5>
J 0
(-2665 3360);
DISPLAY 0.659574 (-2665 3360);
PAINT MONO (-2665 3360);
DISPLAY INVISIBLE (-2665 3360);
FORCEPROP 1 LASTPIN (-2675 3350) BN 5
J 0
(-2687 3358);
DISPLAY 0.680851 (-2687 3358);
PAINT GREEN (-2687 3358);
FORCEPROP 2 LAST CDS_LIB standard
J 0
(-2625 3350);
PAINT MONO (-2625 3350);
DISPLAY INVISIBLE (-2625 3350);
FORCEPROP 1 LAST BODY_TYPE PLUMBING
J 0
(-2625 3400);
DISPLAY 0.872340 (-2625 3400);
PAINT GREEN (-2625 3400);
DISPLAY INVISIBLE (-2625 3400);
FORCEPROP 1 LAST HDL_TAP TRUE
J 0
(-2300 3225);
DISPLAY 0.872340 (-2300 3225);
DISPLAY INVISIBLE (-2300 3225);
FORCEPROP 1 LAST PATH I86
J 0
(-2627 3350);
DISPLAY 0.872340 (-2627 3350);
PAINT GREEN (-2627 3350);
DISPLAY INVISIBLE (-2627 3350);
FORCEADD TAP..1
(-2625 3450);
FORCEPROP 3 LASTPIN (-2675 3450) SIG_NAME M_B_CPU1_SA_DQ<7>
J 0
(-2665 3460);
DISPLAY 0.659574 (-2665 3460);
PAINT MONO (-2665 3460);
DISPLAY INVISIBLE (-2665 3460);
FORCEPROP 1 LASTPIN (-2675 3450) BN 7
J 0
(-2687 3458);
DISPLAY 0.680851 (-2687 3458);
PAINT GREEN (-2687 3458);
FORCEPROP 2 LAST CDS_LIB standard
J 0
(-2625 3450);
PAINT MONO (-2625 3450);
DISPLAY INVISIBLE (-2625 3450);
FORCEPROP 1 LAST BODY_TYPE PLUMBING
J 0
(-2625 3500);
DISPLAY 0.872340 (-2625 3500);
PAINT GREEN (-2625 3500);
DISPLAY INVISIBLE (-2625 3500);
FORCEPROP 1 LAST HDL_TAP TRUE
J 0
(-2300 3325);
DISPLAY 0.872340 (-2300 3325);
DISPLAY INVISIBLE (-2300 3325);
FORCEPROP 1 LAST PATH I87
J 0
(-2627 3450);
DISPLAY 0.872340 (-2627 3450);
PAINT GREEN (-2627 3450);
DISPLAY INVISIBLE (-2627 3450);
FORCEADD TAP..1
(-2625 3550);
FORCEPROP 3 LASTPIN (-2675 3550) SIG_NAME M_B_CPU1_SA_DQ<9>
J 0
(-2665 3560);
DISPLAY 0.659574 (-2665 3560);
PAINT MONO (-2665 3560);
DISPLAY INVISIBLE (-2665 3560);
FORCEPROP 1 LASTPIN (-2675 3550) BN 9
J 0
(-2687 3558);
DISPLAY 0.680851 (-2687 3558);
PAINT GREEN (-2687 3558);
FORCEPROP 2 LAST CDS_LIB standard
J 0
(-2625 3550);
PAINT MONO (-2625 3550);
DISPLAY INVISIBLE (-2625 3550);
FORCEPROP 1 LAST BODY_TYPE PLUMBING
J 0
(-2625 3600);
DISPLAY 0.872340 (-2625 3600);
PAINT GREEN (-2625 3600);
DISPLAY INVISIBLE (-2625 3600);
FORCEPROP 1 LAST HDL_TAP TRUE
J 0
(-2300 3425);
DISPLAY 0.872340 (-2300 3425);
DISPLAY INVISIBLE (-2300 3425);
FORCEPROP 1 LAST PATH I88
J 0
(-2627 3550);
DISPLAY 0.872340 (-2627 3550);
PAINT GREEN (-2627 3550);
DISPLAY INVISIBLE (-2627 3550);
FORCEADD TAP..1
(-2625 3500);
FORCEPROP 3 LASTPIN (-2675 3500) SIG_NAME M_B_CPU1_SA_DQ<8>
J 0
(-2665 3510);
DISPLAY 0.659574 (-2665 3510);
PAINT MONO (-2665 3510);
DISPLAY INVISIBLE (-2665 3510);
FORCEPROP 1 LASTPIN (-2675 3500) BN 8
J 0
(-2687 3508);
DISPLAY 0.680851 (-2687 3508);
PAINT GREEN (-2687 3508);
FORCEPROP 2 LAST CDS_LIB standard
J 0
(-2625 3500);
PAINT MONO (-2625 3500);
DISPLAY INVISIBLE (-2625 3500);
FORCEPROP 1 LAST BODY_TYPE PLUMBING
J 0
(-2625 3550);
DISPLAY 0.872340 (-2625 3550);
PAINT GREEN (-2625 3550);
DISPLAY INVISIBLE (-2625 3550);
FORCEPROP 1 LAST HDL_TAP TRUE
J 0
(-2300 3375);
DISPLAY 0.872340 (-2300 3375);
DISPLAY INVISIBLE (-2300 3375);
FORCEPROP 1 LAST PATH I89
J 0
(-2627 3500);
DISPLAY 0.872340 (-2627 3500);
PAINT GREEN (-2627 3500);
DISPLAY INVISIBLE (-2627 3500);
FORCEADD OFFPAGE..1
(-5200 2400);
FORCEPROP 2 LAST $XR3 100 
J 0
(-5452 2364);
DISPLAY 0.638298 (-5452 2364);
PAINT MONO (-5452 2364);
FORCEPROP 2 LAST $XR2 99 
J 0
(-5632 2400);
DISPLAY 0.638298 (-5632 2400);
PAINT MONO (-5632 2400);
FORCEPROP 2 LAST $XR1 98 
J 0
(-5542 2400);
DISPLAY 0.638298 (-5542 2400);
PAINT MONO (-5542 2400);
FORCEPROP 2 LAST $XR0 130 
J 0
(-5452 2400);
DISPLAY 0.638298 (-5452 2400);
PAINT MONO (-5452 2400);
FORCEPROP 2 LAST CDS_LIB standard
J 0
(-5200 2400);
PAINT MONO (-5200 2400);
DISPLAY INVISIBLE (-5200 2400);
FORCEPROP 1 LAST OFFPAGE TRUE
J 0
(-4875 2275);
DISPLAY 0.872340 (-4875 2275);
DISPLAY INVISIBLE (-4875 2275);
FORCEPROP 1 LAST COMMENT_BODY TRUE
J 0
(-5075 2300);
DISPLAY 0.872340 (-5075 2300);
PAINT GREEN (-5075 2300);
DISPLAY INVISIBLE (-5075 2300);
FORCEPROP 2 LAST PATH I9
J 0
(-5150 2475);
DISPLAY 1.021277 (-5150 2475);
DISPLAY INVISIBLE (-5150 2475);
FORCEADD TAP..1
(-2625 3600);
FORCEPROP 3 LASTPIN (-2675 3600) SIG_NAME M_B_CPU1_SA_DQ<10>
J 0
(-2665 3610);
DISPLAY 0.659574 (-2665 3610);
PAINT MONO (-2665 3610);
DISPLAY INVISIBLE (-2665 3610);
FORCEPROP 1 LASTPIN (-2675 3600) BN 10
J 0
(-2687 3608);
DISPLAY 0.680851 (-2687 3608);
PAINT GREEN (-2687 3608);
FORCEPROP 2 LAST CDS_LIB standard
J 0
(-2625 3600);
PAINT MONO (-2625 3600);
DISPLAY INVISIBLE (-2625 3600);
FORCEPROP 1 LAST BODY_TYPE PLUMBING
J 0
(-2625 3650);
DISPLAY 0.872340 (-2625 3650);
PAINT GREEN (-2625 3650);
DISPLAY INVISIBLE (-2625 3650);
FORCEPROP 1 LAST HDL_TAP TRUE
J 0
(-2300 3475);
DISPLAY 0.872340 (-2300 3475);
DISPLAY INVISIBLE (-2300 3475);
FORCEPROP 1 LAST PATH I90
J 0
(-2627 3600);
DISPLAY 0.872340 (-2627 3600);
PAINT GREEN (-2627 3600);
DISPLAY INVISIBLE (-2627 3600);
FORCEADD TAP..1
(-2625 3700);
FORCEPROP 3 LASTPIN (-2675 3700) SIG_NAME M_B_CPU1_SA_DQ<12>
J 0
(-2665 3710);
DISPLAY 0.659574 (-2665 3710);
PAINT MONO (-2665 3710);
DISPLAY INVISIBLE (-2665 3710);
FORCEPROP 1 LASTPIN (-2675 3700) BN 12
J 0
(-2687 3708);
DISPLAY 0.680851 (-2687 3708);
PAINT GREEN (-2687 3708);
FORCEPROP 2 LAST CDS_LIB standard
J 0
(-2625 3700);
PAINT MONO (-2625 3700);
DISPLAY INVISIBLE (-2625 3700);
FORCEPROP 1 LAST BODY_TYPE PLUMBING
J 0
(-2625 3750);
DISPLAY 0.872340 (-2625 3750);
PAINT GREEN (-2625 3750);
DISPLAY INVISIBLE (-2625 3750);
FORCEPROP 1 LAST HDL_TAP TRUE
J 0
(-2300 3575);
DISPLAY 0.872340 (-2300 3575);
DISPLAY INVISIBLE (-2300 3575);
FORCEPROP 1 LAST PATH I91
J 0
(-2627 3700);
DISPLAY 0.872340 (-2627 3700);
PAINT GREEN (-2627 3700);
DISPLAY INVISIBLE (-2627 3700);
FORCEADD TAP..1
(-2625 3650);
FORCEPROP 3 LASTPIN (-2675 3650) SIG_NAME M_B_CPU1_SA_DQ<11>
J 0
(-2665 3660);
DISPLAY 0.659574 (-2665 3660);
PAINT MONO (-2665 3660);
DISPLAY INVISIBLE (-2665 3660);
FORCEPROP 1 LASTPIN (-2675 3650) BN 11
J 0
(-2687 3658);
DISPLAY 0.680851 (-2687 3658);
PAINT GREEN (-2687 3658);
FORCEPROP 2 LAST CDS_LIB standard
J 0
(-2625 3650);
PAINT MONO (-2625 3650);
DISPLAY INVISIBLE (-2625 3650);
FORCEPROP 1 LAST BODY_TYPE PLUMBING
J 0
(-2625 3700);
DISPLAY 0.872340 (-2625 3700);
PAINT GREEN (-2625 3700);
DISPLAY INVISIBLE (-2625 3700);
FORCEPROP 1 LAST HDL_TAP TRUE
J 0
(-2300 3525);
DISPLAY 0.872340 (-2300 3525);
DISPLAY INVISIBLE (-2300 3525);
FORCEPROP 1 LAST PATH I92
J 0
(-2627 3650);
DISPLAY 0.872340 (-2627 3650);
PAINT GREEN (-2627 3650);
DISPLAY INVISIBLE (-2627 3650);
FORCEADD TAP..1
(-2625 3800);
FORCEPROP 3 LASTPIN (-2675 3800) SIG_NAME M_B_CPU1_SA_DQ<14>
J 0
(-2665 3810);
DISPLAY 0.659574 (-2665 3810);
PAINT MONO (-2665 3810);
DISPLAY INVISIBLE (-2665 3810);
FORCEPROP 1 LASTPIN (-2675 3800) BN 14
J 0
(-2687 3808);
DISPLAY 0.680851 (-2687 3808);
PAINT GREEN (-2687 3808);
FORCEPROP 2 LAST CDS_LIB standard
J 0
(-2625 3800);
PAINT MONO (-2625 3800);
DISPLAY INVISIBLE (-2625 3800);
FORCEPROP 1 LAST BODY_TYPE PLUMBING
J 0
(-2625 3850);
DISPLAY 0.872340 (-2625 3850);
PAINT GREEN (-2625 3850);
DISPLAY INVISIBLE (-2625 3850);
FORCEPROP 1 LAST HDL_TAP TRUE
J 0
(-2300 3675);
DISPLAY 0.872340 (-2300 3675);
DISPLAY INVISIBLE (-2300 3675);
FORCEPROP 1 LAST PATH I93
J 0
(-2627 3800);
DISPLAY 0.872340 (-2627 3800);
PAINT GREEN (-2627 3800);
DISPLAY INVISIBLE (-2627 3800);
FORCEADD TAP..1
(-2625 3750);
FORCEPROP 3 LASTPIN (-2675 3750) SIG_NAME M_B_CPU1_SA_DQ<13>
J 0
(-2665 3760);
DISPLAY 0.659574 (-2665 3760);
PAINT MONO (-2665 3760);
DISPLAY INVISIBLE (-2665 3760);
FORCEPROP 1 LASTPIN (-2675 3750) BN 13
J 0
(-2687 3758);
DISPLAY 0.680851 (-2687 3758);
PAINT GREEN (-2687 3758);
FORCEPROP 2 LAST CDS_LIB standard
J 0
(-2625 3750);
PAINT MONO (-2625 3750);
DISPLAY INVISIBLE (-2625 3750);
FORCEPROP 1 LAST BODY_TYPE PLUMBING
J 0
(-2625 3800);
DISPLAY 0.872340 (-2625 3800);
PAINT GREEN (-2625 3800);
DISPLAY INVISIBLE (-2625 3800);
FORCEPROP 1 LAST HDL_TAP TRUE
J 0
(-2300 3625);
DISPLAY 0.872340 (-2300 3625);
DISPLAY INVISIBLE (-2300 3625);
FORCEPROP 1 LAST PATH I94
J 0
(-2627 3750);
DISPLAY 0.872340 (-2627 3750);
PAINT GREEN (-2627 3750);
DISPLAY INVISIBLE (-2627 3750);
FORCEADD TAP..1
(-2625 3850);
FORCEPROP 3 LASTPIN (-2675 3850) SIG_NAME M_B_CPU1_SA_DQ<15>
J 0
(-2665 3860);
DISPLAY 0.659574 (-2665 3860);
PAINT MONO (-2665 3860);
DISPLAY INVISIBLE (-2665 3860);
FORCEPROP 1 LASTPIN (-2675 3850) BN 15
J 0
(-2687 3858);
DISPLAY 0.680851 (-2687 3858);
PAINT GREEN (-2687 3858);
FORCEPROP 2 LAST CDS_LIB standard
J 0
(-2625 3850);
PAINT MONO (-2625 3850);
DISPLAY INVISIBLE (-2625 3850);
FORCEPROP 1 LAST BODY_TYPE PLUMBING
J 0
(-2625 3900);
DISPLAY 0.872340 (-2625 3900);
PAINT GREEN (-2625 3900);
DISPLAY INVISIBLE (-2625 3900);
FORCEPROP 1 LAST HDL_TAP TRUE
J 0
(-2300 3725);
DISPLAY 0.872340 (-2300 3725);
DISPLAY INVISIBLE (-2300 3725);
FORCEPROP 1 LAST PATH I95
J 0
(-2627 3850);
DISPLAY 0.872340 (-2627 3850);
PAINT GREEN (-2627 3850);
DISPLAY INVISIBLE (-2627 3850);
FORCEADD TAP..1
(-2625 3950);
FORCEPROP 3 LASTPIN (-2675 3950) SIG_NAME M_B_CPU1_SA_DQ<17>
J 0
(-2665 3960);
DISPLAY 0.659574 (-2665 3960);
PAINT MONO (-2665 3960);
DISPLAY INVISIBLE (-2665 3960);
FORCEPROP 1 LASTPIN (-2675 3950) BN 17
J 0
(-2687 3958);
DISPLAY 0.680851 (-2687 3958);
PAINT GREEN (-2687 3958);
FORCEPROP 2 LAST CDS_LIB standard
J 0
(-2625 3950);
PAINT MONO (-2625 3950);
DISPLAY INVISIBLE (-2625 3950);
FORCEPROP 1 LAST BODY_TYPE PLUMBING
J 0
(-2625 4000);
DISPLAY 0.872340 (-2625 4000);
PAINT GREEN (-2625 4000);
DISPLAY INVISIBLE (-2625 4000);
FORCEPROP 1 LAST HDL_TAP TRUE
J 0
(-2300 3825);
DISPLAY 0.872340 (-2300 3825);
DISPLAY INVISIBLE (-2300 3825);
FORCEPROP 1 LAST PATH I96
J 0
(-2627 3950);
DISPLAY 0.872340 (-2627 3950);
PAINT GREEN (-2627 3950);
DISPLAY INVISIBLE (-2627 3950);
FORCEADD TAP..1
(-2625 3900);
FORCEPROP 3 LASTPIN (-2675 3900) SIG_NAME M_B_CPU1_SA_DQ<16>
J 0
(-2665 3910);
DISPLAY 0.659574 (-2665 3910);
PAINT MONO (-2665 3910);
DISPLAY INVISIBLE (-2665 3910);
FORCEPROP 1 LASTPIN (-2675 3900) BN 16
J 0
(-2687 3908);
DISPLAY 0.680851 (-2687 3908);
PAINT GREEN (-2687 3908);
FORCEPROP 2 LAST CDS_LIB standard
J 0
(-2625 3900);
PAINT MONO (-2625 3900);
DISPLAY INVISIBLE (-2625 3900);
FORCEPROP 1 LAST BODY_TYPE PLUMBING
J 0
(-2625 3950);
DISPLAY 0.872340 (-2625 3950);
PAINT GREEN (-2625 3950);
DISPLAY INVISIBLE (-2625 3950);
FORCEPROP 1 LAST HDL_TAP TRUE
J 0
(-2300 3775);
DISPLAY 0.872340 (-2300 3775);
DISPLAY INVISIBLE (-2300 3775);
FORCEPROP 1 LAST PATH I97
J 0
(-2627 3900);
DISPLAY 0.872340 (-2627 3900);
PAINT GREEN (-2627 3900);
DISPLAY INVISIBLE (-2627 3900);
FORCEADD TAP..1
(-2625 4050);
FORCEPROP 3 LASTPIN (-2675 4050) SIG_NAME M_B_CPU1_SA_DQ<19>
J 0
(-2665 4060);
DISPLAY 0.659574 (-2665 4060);
PAINT MONO (-2665 4060);
DISPLAY INVISIBLE (-2665 4060);
FORCEPROP 1 LASTPIN (-2675 4050) BN 19
J 0
(-2687 4058);
DISPLAY 0.680851 (-2687 4058);
PAINT GREEN (-2687 4058);
FORCEPROP 2 LAST CDS_LIB standard
J 0
(-2625 4050);
PAINT MONO (-2625 4050);
DISPLAY INVISIBLE (-2625 4050);
FORCEPROP 1 LAST BODY_TYPE PLUMBING
J 0
(-2625 4100);
DISPLAY 0.872340 (-2625 4100);
PAINT GREEN (-2625 4100);
DISPLAY INVISIBLE (-2625 4100);
FORCEPROP 1 LAST HDL_TAP TRUE
J 0
(-2300 3925);
DISPLAY 0.872340 (-2300 3925);
DISPLAY INVISIBLE (-2300 3925);
FORCEPROP 1 LAST PATH I98
J 0
(-2627 4050);
DISPLAY 0.872340 (-2627 4050);
PAINT GREEN (-2627 4050);
DISPLAY INVISIBLE (-2627 4050);
FORCEADD TAP..1
(-2625 4000);
FORCEPROP 3 LASTPIN (-2675 4000) SIG_NAME M_B_CPU1_SA_DQ<18>
J 0
(-2665 4010);
DISPLAY 0.659574 (-2665 4010);
PAINT MONO (-2665 4010);
DISPLAY INVISIBLE (-2665 4010);
FORCEPROP 1 LASTPIN (-2675 4000) BN 18
J 0
(-2687 4008);
DISPLAY 0.680851 (-2687 4008);
PAINT GREEN (-2687 4008);
FORCEPROP 2 LAST CDS_LIB standard
J 0
(-2625 4000);
PAINT MONO (-2625 4000);
DISPLAY INVISIBLE (-2625 4000);
FORCEPROP 1 LAST BODY_TYPE PLUMBING
J 0
(-2625 4050);
DISPLAY 0.872340 (-2625 4050);
PAINT GREEN (-2625 4050);
DISPLAY INVISIBLE (-2625 4050);
FORCEPROP 1 LAST HDL_TAP TRUE
J 0
(-2300 3875);
DISPLAY 0.872340 (-2300 3875);
DISPLAY INVISIBLE (-2300 3875);
FORCEPROP 1 LAST PATH I99
J 0
(-2627 4000);
DISPLAY 0.872340 (-2627 4000);
PAINT GREEN (-2627 4000);
DISPLAY INVISIBLE (-2627 4000);
FORCEADD CAD_NOTE..1
(-775 200);
FORCEPROP 0 LAST S1 PLACE THE BYPASS CAPS CLOSE TO DIMM
J 0
(-900 75);
DISPLAY 1.021277 (-900 75);
PAINT WHITE (-900 75);
FORCEPROP 2 LAST CDS_LIB logical_power
J 0
(-775 200);
PAINT MONO (-775 200);
DISPLAY INVISIBLE (-775 200);
FORCEPROP 1 LAST COMMENT_BODY TRUE
J 0
(-750 300);
DISPLAY 0.978723 (-750 300);
DISPLAY INVISIBLE (-750 300);
FORCEADD QUANTA_TITLE_BLOCK_C..1
(3700 -1100);
FORCEPROP 0 LAST CDS_CON_LAST_MODIFIED Fri Aug 25 14:01:21 2023
J 0
(1815 -1085);
PAINT MONO (1815 -1085);
DISPLAY INVISIBLE (1815 -1085);
FORCEPROP 1 LAST CUSTOM_TXT_CDS <CON_LAST_MODIFIED>
J 0
(1815 -1085);
DISPLAY 0.978723 (1815 -1085);
FORCEPROP 2 LAST CUSTOM_TXT_CDS <XR_PAGE_TITLE>
J 0
(-4190 4150);
DISPLAY 0.638298 (-4190 4150);
PAINT PINK (-4190 4150);
DISPLAY INVISIBLE (-4190 4150);
FORCEPROP 2 LAST CUSTOM_TXT_CDS <Q_NUMBER>
J 0
(2297 -997);
DISPLAY 1.212766 (2297 -997);
FORCEPROP 1 LAST CUSTOM_TXT_CDS <NAME_2>
J 0
(525 -1050);
FORCEPROP 1 LAST CUSTOM_TXT_CDS <NAME_1>
J 0
(525 -925);
FORCEPROP 1 LAST CUSTOM_TXT_CDS <Q_PROJ>
J 0
(1318 -998);
DISPLAY 1.212766 (1318 -998);
FORCEPROP 1 LAST CUSTOM_TXT_CDS <Q_REV>
J 0
(3516 -997);
DISPLAY 1.212766 (3516 -997);
FORCEPROP 1 LAST CUSTOM_TXT_CDS <CON_PAGE_NUM> OF <CON_TOTAL_PAGES>
J 0
(3254 -1082);
DISPLAY 0.978723 (3254 -1082);
FORCEPROP 1 LAST Q_TITLE DDR5 - CPU1 CHB DIMM2(BLACK)
J 0
(-5666 -1074);
DISPLAY 2.446809 (-5666 -1074);
PAINT GREEN (-5666 -1074);
FORCEPROP 1 LAST Q_DEPT 
J 1
(-63 -1051);
DISPLAY 1.957447 (-63 -1051);
PAINT GREEN (-63 -1051);
FORCEPROP 2 LAST CDS_XR_PAGE_TITLE CR-101 : @S9S_MB_2U_LIB.S9S_MB_2U(SCH_1):PAGE101
J 0
(-4190 4150);
DISPLAY 0.638298 (-4190 4150);
PAINT PINK (-4190 4150);
DISPLAY INVISIBLE (-4190 4150);
FORCEPROP 1 LAST COMMENT_BODY TRUE
J 0
(3712 -1113);
DISPLAY 0.978723 (3712 -1113);
PAINT GREEN (3712 -1113);
DISPLAY INVISIBLE (3712 -1113);
FORCEPROP 2 LAST CDS_LIB pure_quanta
J 0
(3700 -1100);
PAINT MONO (3700 -1100);
DISPLAY INVISIBLE (3700 -1100);
FORCEPROP 1 LAST CDS_LMAN_SYM_OUTLINE -9475,6775,100,-125
J 0
(3700 -1100);
DISPLAY 0.468085 (3700 -1100);
PAINT GREEN (3700 -1100);
DISPLAY INVISIBLE (3700 -1100);
FORCEPROP 2 LAST PAGE_BORDER TRUE
J 0
(-4190 4150);
DISPLAY 0.638298 (-4190 4150);
PAINT PINK (-4190 4150);
DISPLAY INVISIBLE (-4190 4150);
WIRE 17 -1 (-2575 4675)(-1850 4675);
FORCEPROP 2 LAST SIG_NAME M_B_CPU1_SA_DQ<31:0>
J 0
(-2510 4685);
DISPLAY 0.680851 (-2510 4685);
PAINT WHITE (-2510 4685);
WIRE 17 -1 (-5150 3275)(-4325 3275);
FORCEPROP 2 LAST SIG_NAME M_B_CPU1_SA_CB<7:0>
J 0
(-5060 3285);
DISPLAY 0.680851 (-5060 3285);
PAINT WHITE (-5060 3285);
WIRE 17 -1 (-4325 3125)(-4325 3175);
WIRE 17 -1 (-4325 3075)(-4325 3125);
WIRE 17 -1 (-4325 3175)(-4325 3225);
WIRE 17 -1 (-4325 3225)(-4325 3275);
WIRE 17 -1 (-4325 3025)(-4325 3075);
WIRE 17 -1 (-4325 2975)(-4325 3025);
WIRE 17 -1 (-4325 2925)(-4325 2975);
WIRE 17 -1 (-5150 2825)(-4325 2825);
FORCEPROP 2 LAST SIG_NAME M_B_CPU1_SB_CB<7:0>
J 0
(-5060 2835);
DISPLAY 0.680851 (-5060 2835);
PAINT WHITE (-5060 2835);
WIRE 17 -1 (-4325 4375)(-4325 4425);
WIRE 17 -1 (-4325 4425)(-4325 4475);
WIRE 17 -1 (-4325 4475)(-4325 4525);
WIRE 17 -1 (-4325 4525)(-4325 4575);
WIRE 17 -1 (-4325 4575)(-4325 4625);
WIRE 17 -1 (-4325 4625)(-4325 4675);
WIRE 17 -1 (-5150 4675)(-4325 4675);
FORCEPROP 2 LAST SIG_NAME M_B_CPU1_SA_CA<6:0>
J 0
(-5060 4685);
DISPLAY 0.680851 (-5060 4685);
PAINT WHITE (-5060 4685);
WIRE 17 -1 (-4325 3975)(-4325 4025);
WIRE 17 -1 (-4325 4025)(-4325 4075);
WIRE 17 -1 (-4325 4075)(-4325 4125);
WIRE 17 -1 (-4325 4125)(-4325 4175);
WIRE 17 -1 (-4325 4175)(-4325 4225);
WIRE 17 -1 (-4325 4225)(-4325 4275);
WIRE 17 -1 (-5150 4275)(-4325 4275);
FORCEPROP 2 LAST SIG_NAME M_B_CPU1_SB_CA<6:0>
J 0
(-5060 4285);
DISPLAY 0.680851 (-5060 4285);
PAINT WHITE (-5060 4285);
WIRE 17 -1 (-4325 2775)(-4325 2825);
WIRE 17 -1 (-4325 2725)(-4325 2775);
WIRE 17 -1 (-4325 2675)(-4325 2725);
WIRE 17 -1 (-4325 2625)(-4325 2675);
WIRE 17 -1 (-4325 2575)(-4325 2625);
WIRE 17 -1 (-4325 2525)(-4325 2575);
WIRE 17 -1 (-4325 2475)(-4325 2525);
WIRE 17 -1 (-2575 4625)(-2575 4675);
WIRE 17 -1 (-2575 4575)(-2575 4625);
WIRE 17 -1 (-2575 4525)(-2575 4575);
WIRE 17 -1 (-2575 4475)(-2575 4525);
WIRE 17 -1 (-2575 4425)(-2575 4475);
WIRE 17 -1 (-2575 4375)(-2575 4425);
WIRE 17 -1 (-2575 4325)(-2575 4375);
WIRE 17 -1 (-2575 4275)(-2575 4325);
WIRE 17 -1 (-2575 4225)(-2575 4275);
WIRE 17 -1 (-2575 4175)(-2575 4225);
WIRE 17 -1 (-2575 4125)(-2575 4175);
WIRE 17 -1 (-2575 4075)(-2575 4125);
WIRE 17 -1 (-2575 4025)(-2575 4075);
WIRE 17 -1 (-2575 3975)(-2575 4025);
WIRE 17 -1 (-2575 3925)(-2575 3975);
WIRE 17 -1 (-2575 3875)(-2575 3925);
WIRE 17 -1 (-2575 3825)(-2575 3875);
WIRE 17 -1 (-2575 3775)(-2575 3825);
WIRE 17 -1 (-2575 3725)(-2575 3775);
WIRE 17 -1 (-2575 3675)(-2575 3725);
WIRE 17 -1 (-2575 3625)(-2575 3675);
WIRE 17 -1 (-2575 3575)(-2575 3625);
WIRE 17 -1 (-2575 3525)(-2575 3575);
WIRE 17 -1 (-2575 3475)(-2575 3525);
WIRE 17 -1 (-2575 3425)(-2575 3475);
WIRE 17 -1 (-2575 3375)(-2575 3425);
WIRE 17 -1 (-2575 3325)(-2575 3375);
WIRE 17 -1 (-2575 3275)(-2575 3325);
WIRE 17 -1 (-2575 3225)(-2575 3275);
WIRE 17 -1 (-2575 3175)(-2575 3225);
WIRE 17 -1 (-2575 3125)(-2575 3175);
WIRE 17 -1 (-2575 3025)(-1850 3025);
FORCEPROP 2 LAST SIG_NAME M_B_CPU1_SB_DQ<31:0>
J 0
(-2510 3035);
DISPLAY 0.680851 (-2510 3035);
PAINT WHITE (-2510 3035);
WIRE 17 -1 (-2575 2975)(-2575 3025);
WIRE 17 -1 (-2575 2925)(-2575 2975);
WIRE 17 -1 (-2575 2875)(-2575 2925);
WIRE 17 -1 (-2575 2825)(-2575 2875);
WIRE 17 -1 (-2575 2775)(-2575 2825);
WIRE 17 -1 (-2575 2725)(-2575 2775);
WIRE 17 -1 (-2575 2675)(-2575 2725);
WIRE 17 -1 (-2575 2625)(-2575 2675);
WIRE 17 -1 (-2575 2575)(-2575 2625);
WIRE 17 -1 (-2575 2525)(-2575 2575);
WIRE 17 -1 (-2575 2475)(-2575 2525);
WIRE 17 -1 (-2575 2425)(-2575 2475);
WIRE 17 -1 (-2575 2375)(-2575 2425);
WIRE 17 -1 (-2575 2325)(-2575 2375);
WIRE 17 -1 (-2575 2275)(-2575 2325);
WIRE 17 -1 (-2575 2225)(-2575 2275);
WIRE 17 -1 (-2575 2175)(-2575 2225);
WIRE 17 -1 (-2575 2125)(-2575 2175);
WIRE 17 -1 (-2575 2075)(-2575 2125);
WIRE 17 -1 (-2575 2025)(-2575 2075);
WIRE 17 -1 (-2575 1975)(-2575 2025);
WIRE 17 -1 (-2575 1925)(-2575 1975);
WIRE 17 -1 (-2575 1875)(-2575 1925);
WIRE 17 -1 (-2575 1825)(-2575 1875);
WIRE 17 -1 (-2575 1775)(-2575 1825);
WIRE 17 -1 (-2575 1725)(-2575 1775);
WIRE 17 -1 (-2575 1675)(-2575 1725);
WIRE 17 -1 (-2575 1625)(-2575 1675);
WIRE 17 -1 (-2575 1575)(-2575 1625);
WIRE 17 -1 (-2575 1525)(-2575 1575);
WIRE 17 -1 (-2575 1475)(-2575 1525);
WIRE 17 -1 (175 2725)(175 2825);
WIRE 17 -1 (175 2825)(175 2925);
WIRE 17 -1 (175 2925)(175 3025);
WIRE 17 -1 (175 3125)(175 3025);
WIRE 17 -1 (175 3125)(175 3225);
WIRE 17 -1 (175 3225)(175 3325);
WIRE 17 -1 (175 3325)(175 3425);
WIRE 17 -1 (175 3425)(175 3525);
WIRE 17 -1 (175 3525)(175 3625);
WIRE 17 -1 (175 3625)(1200 3625);
FORCEPROP 2 LAST SIG_NAME M_B_CPU1_SB_DQS_DP<9:0>
J 0
(415 3635);
DISPLAY 0.680851 (415 3635);
PAINT WHITE (415 3635);
WIRE 17 -1 (175 3775)(175 3875);
WIRE 17 -1 (175 3875)(175 3975);
WIRE 17 -1 (175 3975)(175 4075);
WIRE 17 -1 (175 4175)(175 4075);
WIRE 17 -1 (175 4175)(175 4275);
WIRE 17 -1 (175 4275)(175 4375);
WIRE 17 -1 (175 4375)(175 4475);
WIRE 17 -1 (175 4475)(175 4575);
WIRE 17 -1 (175 4575)(175 4675);
WIRE 17 -1 (175 4675)(1200 4675);
FORCEPROP 2 LAST SIG_NAME M_B_CPU1_SA_DQS_DP<9:0>
J 0
(415 4685);
DISPLAY 0.680851 (415 4685);
PAINT WHITE (415 4685);
WIRE 17 -1 (350 2675)(350 2775);
WIRE 17 -1 (350 2775)(350 2875);
WIRE 17 -1 (350 2875)(350 2975);
WIRE 17 -1 (350 3075)(350 2975);
WIRE 17 -1 (350 3075)(350 3175);
WIRE 17 -1 (350 3175)(350 3275);
WIRE 17 -1 (350 3275)(350 3375);
WIRE 17 -1 (350 3375)(350 3475);
WIRE 17 -1 (350 3475)(350 3575);
WIRE 17 -1 (350 3575)(1200 3575);
FORCEPROP 2 LAST SIG_NAME M_B_CPU1_SB_DQS_DN<9:0>
J 0
(415 3585);
DISPLAY 0.680851 (415 3585);
PAINT WHITE (415 3585);
WIRE 17 -1 (350 3725)(350 3825);
WIRE 17 -1 (350 3825)(350 3925);
WIRE 17 -1 (350 3925)(350 4025);
WIRE 17 -1 (350 4125)(350 4025);
WIRE 17 -1 (350 4125)(350 4225);
WIRE 17 -1 (350 4225)(350 4325);
WIRE 17 -1 (350 4325)(350 4425);
WIRE 17 -1 (350 4425)(350 4525);
WIRE 17 -1 (350 4525)(350 4625);
WIRE 17 -1 (350 4625)(1200 4625);
FORCEPROP 2 LAST SIG_NAME M_B_CPU1_SA_DQS_DN<9:0>
J 0
(415 4635);
DISPLAY 0.680851 (415 4635);
PAINT WHITE (415 4635);
WIRE 16 -1 (-900 875)(-900 1050);
WIRE 16 -1 (100 1050)(100 1000);
WIRE 16 -1 (1800 5150)(1800 4650);
WIRE 16 -1 (-5100 2475)(-5100 2200);
WIRE 16 -1 (-900 675)(-900 450);
WIRE 16 -1 (725 450)(725 525);
WIRE 16 -1 (1800 1000)(1800 1400);
WIRE 16 -1 (3500 1300)(3500 1000);
WIRE 16 -1 (3500 1350)(3500 1300);
WIRE 16 -1 (3250 1300)(3500 1300);
WIRE 16 -1 (-4050 325)(-4050 400);
WIRE 16 3135 (1350 1275)(-1250 1275);
WIRE 16 3135 (1350 -25)(1350 1275);
WIRE 16 3135 (-1250 1275)(-1250 -25);
WIRE 16 3135 (-1250 -25)(1350 -25);
WIRE 16 -1 (-3950 1875)(-3975 1875);
WIRE 16 -1 (-5175 1950)(-3950 1950);
FORCEPROP 2 LAST SIG_NAME I3C_SPD_DDRABCD_CPU1_LVC1_SCL
J 0
(-5010 1960);
DISPLAY 0.680851 (-5010 1960);
PAINT WHITE (-5010 1960);
WIRE 16 -1 (-3950 1950)(-3950 1875);
WIRE 16 -1 (-4050 2150)(-5075 2150);
FORCEPROP 2 LAST SIG_NAME PD_CHB_CPU1_DIMM2_SAA
J 0
(-5085 2160);
DISPLAY 0.680851 (-5085 2160);
PAINT WHITE (-5085 2160);
WIRE 16 -1 (-4050 2100)(-5075 2100);
FORCEPROP 2 LAST SIG_NAME I3C_SPD_DDRABCD_CPU1_LVC1_SDA
J 0
(-5085 2110);
DISPLAY 0.680851 (-5085 2110);
PAINT WHITE (-5085 2110);
WIRE 16 -1 (-5100 2200)(-4050 2200);
WIRE 16 -1 (-5575 1950)(-5375 1950);
WIRE 16 -1 (-5575 1950)(-5575 2050);
WIRE 16 -1 (-4050 2050)(-5575 2050);
FORCEPROP 2 LAST SIG_NAME I3C_SPD_DDRABCD_CPU1_LVC1_SCL_R4
J 0
(-5110 2060);
DISPLAY 0.680851 (-5110 2060);
PAINT WHITE (-5110 2060);
WIRE 16 -1 (-4050 2300)(-5150 2300);
FORCEPROP 2 LAST SIG_NAME M_B_CPU1_ALERT_N
J 0
(-5062 2309);
DISPLAY 0.680851 (-5062 2309);
PAINT WHITE (-5062 2309);
WIRE 16 -1 (-4425 2400)(-5150 2400);
FORCEPROP 2 LAST SIG_NAME RST_M_AB_CPU1_FPGA_N
J 0
(-5062 2409);
DISPLAY 0.680851 (-5062 2409);
PAINT WHITE (-5062 2409);
WIRE 16 -1 (-4425 2400)(-4425 2350);
WIRE 16 -1 (-4425 2350)(-4050 2350);
WIRE 16 -1 (-4050 1800)(-5150 1800);
FORCEPROP 2 LAST SIG_NAME PWRGD_CHB_CPU1_DIMM2
J 0
(-5062 1809);
DISPLAY 0.680851 (-5062 1809);
PAINT WHITE (-5062 1809);
WIRE 16 -1 (-4050 1700)(-5150 1700);
FORCEPROP 2 LAST SIG_NAME TP_CHB_CPU1_DIMM2_FRU_6
J 0
(-5062 1709);
DISPLAY 0.680851 (-5062 1709);
PAINT WHITE (-5062 1709);
WIRE 16 -1 (-4050 1650)(-5150 1650);
FORCEPROP 2 LAST SIG_NAME TP_CHB_CPU1_DIMM2_FRU_5
J 0
(-5062 1659);
DISPLAY 0.680851 (-5062 1659);
PAINT WHITE (-5062 1659);
WIRE 16 -1 (-25 4500)(250 4500);
WIRE 16 -1 (-25 4600)(250 4600);
WIRE 16 -1 (-25 4400)(250 4400);
WIRE 16 -1 (-25 4300)(250 4300);
WIRE 16 -1 (-25 4200)(250 4200);
WIRE 16 -1 (-25 4100)(250 4100);
WIRE 16 -1 (-25 4000)(250 4000);
WIRE 16 -1 (-25 3900)(250 3900);
WIRE 16 -1 (-25 3800)(250 3800);
WIRE 16 -1 (-25 3700)(250 3700);
WIRE 16 -1 (-25 3550)(250 3550);
WIRE 16 -1 (-25 3450)(250 3450);
WIRE 16 -1 (-25 3350)(250 3350);
WIRE 16 -1 (-25 3250)(250 3250);
WIRE 16 -1 (-25 3150)(250 3150);
WIRE 16 -1 (-25 3050)(250 3050);
WIRE 16 -1 (-25 2950)(250 2950);
WIRE 16 -1 (-25 2850)(250 2850);
WIRE 16 -1 (-25 2750)(250 2750);
WIRE 16 -1 (-25 2650)(250 2650);
WIRE 16 -1 (-25 4650)(75 4650);
WIRE 16 -1 (-25 4550)(75 4550);
WIRE 16 -1 (-25 4450)(75 4450);
WIRE 16 -1 (-25 4350)(75 4350);
WIRE 16 -1 (-25 4250)(75 4250);
WIRE 16 -1 (-25 4150)(75 4150);
WIRE 16 -1 (-25 4050)(75 4050);
WIRE 16 -1 (-25 3950)(75 3950);
WIRE 16 -1 (-25 3850)(75 3850);
WIRE 16 -1 (-25 3750)(75 3750);
WIRE 16 -1 (-25 3600)(75 3600);
WIRE 16 -1 (-25 3500)(75 3500);
WIRE 16 -1 (-25 3400)(75 3400);
WIRE 16 -1 (-25 3300)(75 3300);
WIRE 16 -1 (-25 3200)(75 3200);
WIRE 16 -1 (-25 3100)(75 3100);
WIRE 16 -1 (-25 3000)(75 3000);
WIRE 16 -1 (-25 2900)(75 2900);
WIRE 16 -1 (-25 2800)(75 2800);
WIRE 16 -1 (-25 2700)(75 2700);
WIRE 16 -1 (-4225 2600)(-4050 2600);
WIRE 16 -1 (-2850 2100)(-2675 2100);
WIRE 16 -1 (-2850 2250)(-2675 2250);
WIRE 16 -1 (2050 4550)(1800 4550);
WIRE 16 -1 (1800 4600)(1800 4550);
WIRE 16 -1 (1800 4600)(2050 4600);
WIRE 16 -1 (1800 4650)(1800 4600);
WIRE 16 -1 (2050 4650)(1800 4650);
WIRE 16 -1 (1800 1400)(2050 1400);
WIRE 16 -1 (1800 1400)(1800 1450);
WIRE 16 -1 (1800 1450)(2050 1450);
WIRE 16 -1 (1800 1450)(1800 1500);
WIRE 16 -1 (1800 1500)(2050 1500);
WIRE 16 -1 (1800 1500)(1800 1550);
WIRE 16 -1 (1800 1550)(2050 1550);
WIRE 16 -1 (1800 1550)(1800 1600);
WIRE 16 -1 (1800 1600)(2050 1600);
WIRE 16 -1 (1800 1600)(1800 1650);
WIRE 16 -1 (1800 1650)(2050 1650);
WIRE 16 -1 (1800 1650)(1800 1700);
WIRE 16 -1 (1800 1700)(2050 1700);
WIRE 16 -1 (1800 1700)(1800 1750);
WIRE 16 -1 (1800 1750)(2050 1750);
WIRE 16 -1 (1800 1750)(1800 1800);
WIRE 16 -1 (1800 1800)(2050 1800);
WIRE 16 -1 (1800 1800)(1800 1850);
WIRE 16 -1 (1800 1850)(2050 1850);
WIRE 16 -1 (1800 1850)(1800 1900);
WIRE 16 -1 (2050 1900)(1800 1900);
WIRE 16 -1 (1800 1900)(1800 1950);
WIRE 16 -1 (1800 1950)(2050 1950);
WIRE 16 -1 (1800 1950)(1800 2000);
WIRE 16 -1 (1800 2000)(2050 2000);
WIRE 16 -1 (1800 2000)(1800 2050);
WIRE 16 -1 (1800 2050)(2050 2050);
WIRE 16 -1 (1800 2050)(1800 2100);
WIRE 16 -1 (1800 2100)(2050 2100);
WIRE 16 -1 (1800 2100)(1800 2150);
WIRE 16 -1 (1800 2150)(2050 2150);
WIRE 16 -1 (1800 2150)(1800 2200);
WIRE 16 -1 (1800 2200)(2050 2200);
WIRE 16 -1 (1800 2200)(1800 2250);
WIRE 16 -1 (1800 2250)(2050 2250);
WIRE 16 -1 (1800 2250)(1800 2300);
WIRE 16 -1 (1800 2300)(2050 2300);
WIRE 16 -1 (1800 2300)(1800 2350);
WIRE 16 -1 (1800 2350)(2050 2350);
WIRE 16 -1 (1800 2350)(1800 2400);
WIRE 16 -1 (2050 2400)(1800 2400);
WIRE 16 -1 (1800 2400)(1800 2450);
WIRE 16 -1 (1800 2450)(2050 2450);
WIRE 16 -1 (1800 2450)(1800 2500);
WIRE 16 -1 (1800 2500)(2050 2500);
WIRE 16 -1 (1800 2500)(1800 2550);
WIRE 16 -1 (1800 2550)(2050 2550);
WIRE 16 -1 (1800 2550)(1800 2600);
WIRE 16 -1 (1800 2600)(2050 2600);
WIRE 16 -1 (1800 2600)(1800 2650);
WIRE 16 -1 (1800 2650)(2050 2650);
WIRE 16 -1 (1800 2650)(1800 2700);
WIRE 16 -1 (1800 2700)(2050 2700);
WIRE 16 -1 (1800 2700)(1800 2750);
WIRE 16 -1 (1800 2750)(2050 2750);
WIRE 16 -1 (1800 2750)(1800 2800);
WIRE 16 -1 (1800 2800)(2050 2800);
WIRE 16 -1 (1800 2800)(1800 2850);
WIRE 16 -1 (1800 2850)(2050 2850);
WIRE 16 -1 (1800 2850)(1800 2900);
WIRE 16 -1 (2050 2900)(1800 2900);
WIRE 16 -1 (1800 2900)(1800 2950);
WIRE 16 -1 (1800 2950)(2050 2950);
WIRE 16 -1 (1800 2950)(1800 3000);
WIRE 16 -1 (1800 3000)(2050 3000);
WIRE 16 -1 (1800 3000)(1800 3050);
WIRE 16 -1 (1800 3050)(2050 3050);
WIRE 16 -1 (1800 3050)(1800 3100);
WIRE 16 -1 (1800 3100)(2050 3100);
WIRE 16 -1 (1800 3100)(1800 3150);
WIRE 16 -1 (1800 3150)(2050 3150);
WIRE 16 -1 (1800 3150)(1800 3200);
WIRE 16 -1 (1800 3200)(2050 3200);
WIRE 16 -1 (1800 3200)(1800 3250);
WIRE 16 -1 (1800 3250)(2050 3250);
WIRE 16 -1 (1800 3250)(1800 3300);
WIRE 16 -1 (1800 3300)(2050 3300);
WIRE 16 -1 (1800 3300)(1800 3350);
WIRE 16 -1 (1800 3350)(2050 3350);
WIRE 16 -1 (1800 3350)(1800 3400);
WIRE 16 -1 (2050 3400)(1800 3400);
WIRE 16 -1 (1800 3400)(1800 3450);
WIRE 16 -1 (1800 3450)(2050 3450);
WIRE 16 -1 (1800 3450)(1800 3500);
WIRE 16 -1 (1800 3500)(2050 3500);
WIRE 16 -1 (1800 3500)(1800 3550);
WIRE 16 -1 (1800 3550)(2050 3550);
WIRE 16 -1 (1800 3550)(1800 3600);
WIRE 16 -1 (1800 3600)(2050 3600);
WIRE 16 -1 (1800 3600)(1800 3650);
WIRE 16 -1 (1800 3650)(2050 3650);
WIRE 16 -1 (1800 3650)(1800 3700);
WIRE 16 -1 (1800 3700)(2050 3700);
WIRE 16 -1 (1800 3700)(1800 3750);
WIRE 16 -1 (1800 3750)(2050 3750);
WIRE 16 -1 (1800 3750)(1800 3800);
WIRE 16 -1 (1800 3800)(2050 3800);
WIRE 16 -1 (1800 3800)(1800 3850);
WIRE 16 -1 (1800 3850)(2050 3850);
WIRE 16 -1 (1800 3850)(1800 3900);
WIRE 16 -1 (2050 3900)(1800 3900);
WIRE 16 -1 (1800 3900)(1800 3950);
WIRE 16 -1 (1800 3950)(2050 3950);
WIRE 16 -1 (1800 3950)(1800 4000);
WIRE 16 -1 (1800 4000)(2050 4000);
WIRE 16 -1 (1800 4000)(1800 4050);
WIRE 16 -1 (1800 4050)(2050 4050);
WIRE 16 -1 (1800 4050)(1800 4100);
WIRE 16 -1 (1800 4100)(2050 4100);
WIRE 16 -1 (1800 4100)(1800 4150);
WIRE 16 -1 (1800 4150)(2050 4150);
WIRE 16 -1 (1800 4150)(1800 4200);
WIRE 16 -1 (1800 4200)(2050 4200);
WIRE 16 -1 (1800 4200)(1800 4250);
WIRE 16 -1 (1800 4250)(2050 4250);
WIRE 16 -1 (1800 4250)(1800 4300);
WIRE 16 -1 (1800 4300)(2050 4300);
WIRE 16 -1 (1800 4300)(1800 4350);
WIRE 16 -1 (1800 4350)(2050 4350);
WIRE 16 -1 (1800 4350)(1800 4400);
WIRE 16 -1 (2050 4400)(1800 4400);
WIRE 16 -1 (1800 4400)(1800 4450);
WIRE 16 -1 (1800 4450)(2050 4450);
WIRE 16 -1 (1800 4450)(1800 4500);
WIRE 16 -1 (2050 4500)(1800 4500);
WIRE 16 -1 (-2850 4150)(-2675 4150);
WIRE 16 -1 (-2850 4100)(-2675 4100);
WIRE 16 -1 (-2850 4050)(-2675 4050);
WIRE 16 -1 (-2850 3450)(-2675 3450);
WIRE 16 -1 (-2850 3500)(-2675 3500);
WIRE 16 -1 (-2850 2150)(-2675 2150);
WIRE 16 -1 (-2850 2050)(-2675 2050);
WIRE 16 -1 (-4050 1400)(-5150 1400);
FORCEPROP 2 LAST SIG_NAME TP_CHB_CPU1_DIMM2_FRU_0
J 0
(-5062 1409);
DISPLAY 0.680851 (-5062 1409);
PAINT WHITE (-5062 1409);
WIRE 16 -1 (-4050 1450)(-5150 1450);
FORCEPROP 2 LAST SIG_NAME TP_CHB_CPU1_DIMM2_FRU_1
J 0
(-5062 1459);
DISPLAY 0.680851 (-5062 1459);
PAINT WHITE (-5062 1459);
WIRE 16 -1 (-4050 1500)(-5150 1500);
FORCEPROP 2 LAST SIG_NAME TP_CHB_CPU1_DIMM2_FRU_2
J 0
(-5062 1509);
DISPLAY 0.680851 (-5062 1509);
PAINT WHITE (-5062 1509);
WIRE 16 -1 (-4050 1550)(-5150 1550);
FORCEPROP 2 LAST SIG_NAME TP_CHB_CPU1_DIMM2_FRU_3
J 0
(-5062 1559);
DISPLAY 0.680851 (-5062 1559);
PAINT WHITE (-5062 1559);
WIRE 16 -1 (-4050 1600)(-5150 1600);
FORCEPROP 2 LAST SIG_NAME TP_CHB_CPU1_DIMM2_FRU_4
J 0
(-5062 1609);
DISPLAY 0.680851 (-5062 1609);
PAINT WHITE (-5062 1609);
WIRE 16 -1 (-4050 3800)(-5150 3800);
FORCEPROP 2 LAST SIG_NAME M_B_CPU1_SB_PAR
J 0
(-5062 3809);
DISPLAY 0.680851 (-5062 3809);
PAINT WHITE (-5062 3809);
WIRE 16 -1 (-4050 3850)(-5150 3850);
FORCEPROP 2 LAST SIG_NAME M_B_CPU1_SA_PAR
J 0
(-5062 3859);
DISPLAY 0.680851 (-5062 3859);
PAINT WHITE (-5062 3859);
WIRE 16 -1 (-4050 1200)(-5150 1200);
FORCEPROP 2 LAST SIG_NAME M_B_CPU1_SB_RSP<1>
J 0
(-5062 1209);
DISPLAY 0.680851 (-5062 1209);
PAINT WHITE (-5062 1209);
WIRE 16 -1 (-4050 1250)(-5150 1250);
FORCEPROP 2 LAST SIG_NAME M_B_CPU1_SA_RSP<1>
J 0
(-5062 1259);
DISPLAY 0.680851 (-5062 1259);
PAINT WHITE (-5062 1259);
WIRE 16 -1 (-2850 1450)(-2675 1450);
WIRE 16 -1 (-2850 1500)(-2675 1500);
WIRE 16 -1 (-2850 1550)(-2675 1550);
WIRE 16 -1 (-2850 1600)(-2675 1600);
WIRE 16 -1 (-2850 1650)(-2675 1650);
WIRE 16 -1 (-2850 1700)(-2675 1700);
WIRE 16 -1 (-2850 1750)(-2675 1750);
WIRE 16 -1 (-2850 1800)(-2675 1800);
WIRE 16 -1 (-2850 1850)(-2675 1850);
WIRE 16 -1 (-2850 1900)(-2675 1900);
WIRE 16 -1 (-2850 1950)(-2675 1950);
WIRE 16 -1 (-2850 2000)(-2675 2000);
WIRE 16 -1 (-2850 2200)(-2675 2200);
WIRE 16 -1 (-2850 2300)(-2675 2300);
WIRE 16 -1 (-2850 2350)(-2675 2350);
WIRE 16 -1 (-2850 2400)(-2675 2400);
WIRE 16 -1 (-2850 2450)(-2675 2450);
WIRE 16 -1 (-2850 2500)(-2675 2500);
WIRE 16 -1 (-2850 2550)(-2675 2550);
WIRE 16 -1 (-2850 2600)(-2675 2600);
WIRE 16 -1 (-2850 2650)(-2675 2650);
WIRE 16 -1 (-2850 2700)(-2675 2700);
WIRE 16 -1 (-2850 2750)(-2675 2750);
WIRE 16 -1 (-2850 2800)(-2675 2800);
WIRE 16 -1 (-2850 2850)(-2675 2850);
WIRE 16 -1 (-2850 2900)(-2675 2900);
WIRE 16 -1 (-2850 2950)(-2675 2950);
WIRE 16 -1 (-2850 3000)(-2675 3000);
WIRE 16 -1 (-2850 3100)(-2675 3100);
WIRE 16 -1 (-2850 3150)(-2675 3150);
WIRE 16 -1 (-2850 3200)(-2675 3200);
WIRE 16 -1 (-2850 3250)(-2675 3250);
WIRE 16 -1 (-2850 3300)(-2675 3300);
WIRE 16 -1 (-2850 3350)(-2675 3350);
WIRE 16 -1 (-2850 3400)(-2675 3400);
WIRE 16 -1 (-2850 3550)(-2675 3550);
WIRE 16 -1 (-2850 3600)(-2675 3600);
WIRE 16 -1 (-2850 3650)(-2675 3650);
WIRE 16 -1 (-2850 3700)(-2675 3700);
WIRE 16 -1 (-2850 3750)(-2675 3750);
WIRE 16 -1 (-2850 3800)(-2675 3800);
WIRE 16 -1 (-2850 3850)(-2675 3850);
WIRE 16 -1 (-2850 3900)(-2675 3900);
WIRE 16 -1 (-2850 3950)(-2675 3950);
WIRE 16 -1 (-2850 4000)(-2675 4000);
WIRE 16 -1 (-2850 4200)(-2675 4200);
WIRE 16 -1 (-2850 4250)(-2675 4250);
WIRE 16 -1 (-2850 4300)(-2675 4300);
WIRE 16 -1 (-2850 4350)(-2675 4350);
WIRE 16 -1 (-2850 4400)(-2675 4400);
WIRE 16 -1 (-2850 4450)(-2675 4450);
WIRE 16 -1 (-2850 4500)(-2675 4500);
WIRE 16 -1 (-2850 4550)(-2675 4550);
WIRE 16 -1 (-2850 4600)(-2675 4600);
WIRE 16 -1 (-4050 3550)(-5150 3550);
FORCEPROP 2 LAST SIG_NAME M_B_CPU1_SB_CS_N<3>
J 0
(-5062 3559);
DISPLAY 0.680851 (-5062 3559);
PAINT WHITE (-5062 3559);
WIRE 16 -1 (-4050 3700)(-5150 3700);
FORCEPROP 2 LAST SIG_NAME M_B_CPU1_SA_CS_N<3>
J 0
(-5062 3709);
DISPLAY 0.680851 (-5062 3709);
PAINT WHITE (-5062 3709);
WIRE 16 -1 (-4050 3500)(-5150 3500);
FORCEPROP 2 LAST SIG_NAME M_B_CPU1_SB_CS_N<2>
J 0
(-5062 3509);
DISPLAY 0.680851 (-5062 3509);
PAINT WHITE (-5062 3509);
WIRE 16 -1 (-4050 3650)(-5150 3650);
FORCEPROP 2 LAST SIG_NAME M_B_CPU1_SA_CS_N<2>
J 0
(-5062 3659);
DISPLAY 0.680851 (-5062 3659);
PAINT WHITE (-5062 3659);
WIRE 16 -1 (-4050 3400)(-5150 3400);
FORCEPROP 2 LAST SIG_NAME M_B_CPU1_CLK_DP<1>
J 0
(-5062 3409);
DISPLAY 0.680851 (-5062 3409);
PAINT WHITE (-5062 3409);
WIRE 16 -1 (-4050 3350)(-5150 3350);
FORCEPROP 2 LAST SIG_NAME M_B_CPU1_CLK_DN<1>
J 0
(-5062 3359);
DISPLAY 0.680851 (-5062 3359);
PAINT WHITE (-5062 3359);
WIRE 16 -1 (-4225 2450)(-4050 2450);
WIRE 16 -1 (-4225 2500)(-4050 2500);
WIRE 16 -1 (-4225 2550)(-4050 2550);
WIRE 16 -1 (-4225 2650)(-4050 2650);
WIRE 16 -1 (-4225 2700)(-4050 2700);
WIRE 16 -1 (-4225 2750)(-4050 2750);
WIRE 16 -1 (-4225 2900)(-4050 2900);
WIRE 16 -1 (-4225 3000)(-4050 3000);
WIRE 16 -1 (-4225 3050)(-4050 3050);
WIRE 16 -1 (-4225 3150)(-4050 3150);
WIRE 16 -1 (-4225 3200)(-4050 3200);
WIRE 16 -1 (-4225 4250)(-4050 4250);
WIRE 16 -1 (-4225 4650)(-4050 4650);
WIRE 16 -1 (-4225 4200)(-4050 4200);
WIRE 16 -1 (-4225 4600)(-4050 4600);
WIRE 16 -1 (-4225 4150)(-4050 4150);
WIRE 16 -1 (-4225 4550)(-4050 4550);
WIRE 16 -1 (-4225 4100)(-4050 4100);
WIRE 16 -1 (-4225 4500)(-4050 4500);
WIRE 16 -1 (-4225 4050)(-4050 4050);
WIRE 16 -1 (-4225 4450)(-4050 4450);
WIRE 16 -1 (-4225 4000)(-4050 4000);
WIRE 16 -1 (-4225 4400)(-4050 4400);
WIRE 16 -1 (-4225 3950)(-4050 3950);
WIRE 16 -1 (-4225 4350)(-4050 4350);
WIRE 16 -1 (-4225 2800)(-4050 2800);
WIRE 16 -1 (-4225 2950)(-4050 2950);
WIRE 16 -1 (-4225 3100)(-4050 3100);
WIRE 16 -1 (-4225 3250)(-4050 3250);
WIRE 16 -1 (-2850 4650)(-2675 4650);
WIRE 16 -1 (3250 1350)(3500 1350);
WIRE 16 -1 (3250 1400)(3500 1400);
WIRE 16 -1 (3500 1400)(3500 1350);
WIRE 16 -1 (3250 1500)(3500 1500);
WIRE 16 -1 (3500 1500)(3500 1400);
WIRE 16 -1 (3500 1550)(3500 1500);
WIRE 16 -1 (3250 1550)(3500 1550);
WIRE 16 -1 (3250 1600)(3500 1600);
WIRE 16 -1 (3500 1550)(3500 1600);
WIRE 16 -1 (3250 1650)(3500 1650);
WIRE 16 -1 (3500 1650)(3500 1600);
WIRE 16 -1 (3250 1700)(3500 1700);
WIRE 16 -1 (3500 1700)(3500 1650);
WIRE 16 -1 (3250 1750)(3500 1750);
WIRE 16 -1 (3500 1750)(3500 1700);
WIRE 16 -1 (3250 1800)(3500 1800);
WIRE 16 -1 (3500 1800)(3500 1750);
WIRE 16 -1 (3250 1850)(3500 1850);
WIRE 16 -1 (3500 1850)(3500 1800);
WIRE 16 -1 (3250 1900)(3500 1900);
WIRE 16 -1 (3500 1900)(3500 1850);
WIRE 16 -1 (3500 1950)(3250 1950);
WIRE 16 -1 (3500 1950)(3500 1900);
WIRE 16 -1 (3500 2000)(3250 2000);
WIRE 16 -1 (3500 2000)(3500 1950);
WIRE 16 -1 (3500 2050)(3500 2000);
WIRE 16 -1 (3500 2050)(3250 2050);
WIRE 16 -1 (3250 2100)(3500 2100);
WIRE 16 -1 (3500 2050)(3500 2100);
WIRE 16 -1 (3500 2150)(3250 2150);
WIRE 16 -1 (3500 2100)(3500 2150);
WIRE 16 -1 (3500 2200)(3250 2200);
WIRE 16 -1 (3500 2200)(3500 2150);
WIRE 16 -1 (3500 2250)(3250 2250);
WIRE 16 -1 (3500 2250)(3500 2200);
WIRE 16 -1 (3500 2300)(3250 2300);
WIRE 16 -1 (3500 2300)(3500 2250);
WIRE 16 -1 (3250 2350)(3500 2350);
WIRE 16 -1 (3500 2350)(3500 2300);
WIRE 16 -1 (3250 2400)(3500 2400);
WIRE 16 -1 (3500 2400)(3500 2350);
WIRE 16 -1 (3250 2450)(3500 2450);
WIRE 16 -1 (3500 2400)(3500 2450);
WIRE 16 -1 (3250 2500)(3500 2500);
WIRE 16 -1 (3500 2500)(3500 2450);
WIRE 16 -1 (3250 2550)(3500 2550);
WIRE 16 -1 (3500 2550)(3500 2500);
WIRE 16 -1 (3500 2600)(3500 2550);
WIRE 16 -1 (3250 2600)(3500 2600);
WIRE 16 -1 (3250 2650)(3500 2650);
WIRE 16 -1 (3500 2650)(3500 2600);
WIRE 16 -1 (3250 2700)(3500 2700);
WIRE 16 -1 (3500 2700)(3500 2650);
WIRE 16 -1 (3500 2750)(3250 2750);
WIRE 16 -1 (3500 2750)(3500 2700);
WIRE 16 -1 (3500 2800)(3250 2800);
WIRE 16 -1 (3500 2800)(3500 2750);
WIRE 16 -1 (3250 2850)(3500 2850);
WIRE 16 -1 (3500 2850)(3500 2800);
WIRE 16 -1 (3250 2900)(3500 2900);
WIRE 16 -1 (3500 2900)(3500 2850);
WIRE 16 -1 (3250 2950)(3500 2950);
WIRE 16 -1 (3500 2900)(3500 2950);
WIRE 16 -1 (3250 3000)(3500 3000);
WIRE 16 -1 (3500 3000)(3500 2950);
WIRE 16 -1 (3250 3050)(3500 3050);
WIRE 16 -1 (3500 3050)(3500 3000);
WIRE 16 -1 (3500 3100)(3500 3050);
WIRE 16 -1 (3250 3100)(3500 3100);
WIRE 16 -1 (3250 3150)(3500 3150);
WIRE 16 -1 (3500 3150)(3500 3100);
WIRE 16 -1 (3250 3200)(3500 3200);
WIRE 16 -1 (3500 3200)(3500 3150);
WIRE 16 -1 (3500 3250)(3250 3250);
WIRE 16 -1 (3500 3250)(3500 3200);
WIRE 16 -1 (3500 3300)(3250 3300);
WIRE 16 -1 (3500 3300)(3500 3250);
WIRE 16 -1 (3250 3350)(3500 3350);
WIRE 16 -1 (3500 3350)(3500 3300);
WIRE 16 -1 (3250 3400)(3500 3400);
WIRE 16 -1 (3500 3400)(3500 3350);
WIRE 16 -1 (3250 3450)(3500 3450);
WIRE 16 -1 (3500 3400)(3500 3450);
WIRE 16 -1 (3250 3500)(3500 3500);
WIRE 16 -1 (3500 3500)(3500 3450);
WIRE 16 -1 (3250 3550)(3500 3550);
WIRE 16 -1 (3500 3550)(3500 3500);
WIRE 16 -1 (3500 3600)(3500 3550);
WIRE 16 -1 (3250 3600)(3500 3600);
WIRE 16 -1 (3250 3650)(3500 3650);
WIRE 16 -1 (3500 3650)(3500 3600);
WIRE 16 -1 (3250 3700)(3500 3700);
WIRE 16 -1 (3500 3700)(3500 3650);
WIRE 16 -1 (3500 3750)(3250 3750);
WIRE 16 -1 (3500 3750)(3500 3700);
WIRE 16 -1 (3500 3800)(3250 3800);
WIRE 16 -1 (3500 3800)(3500 3750);
WIRE 16 -1 (3250 3850)(3500 3850);
WIRE 16 -1 (3500 3850)(3500 3800);
WIRE 16 -1 (3250 3900)(3500 3900);
WIRE 16 -1 (3500 3900)(3500 3850);
WIRE 16 -1 (3250 3950)(3500 3950);
WIRE 16 -1 (3500 3900)(3500 3950);
WIRE 16 -1 (3250 4000)(3500 4000);
WIRE 16 -1 (3500 4000)(3500 3950);
WIRE 16 -1 (3250 4050)(3500 4050);
WIRE 16 -1 (3500 4050)(3500 4000);
WIRE 16 -1 (3500 4100)(3500 4050);
WIRE 16 -1 (3250 4100)(3500 4100);
WIRE 16 -1 (3250 4150)(3500 4150);
WIRE 16 -1 (3500 4150)(3500 4100);
WIRE 16 -1 (3250 4200)(3500 4200);
WIRE 16 -1 (3500 4200)(3500 4150);
WIRE 16 -1 (3250 4250)(3500 4250);
WIRE 16 -1 (3500 4250)(3500 4200);
WIRE 16 -1 (3250 4300)(3500 4300);
WIRE 16 -1 (3500 4300)(3500 4250);
WIRE 16 -1 (3250 4350)(3500 4350);
WIRE 16 -1 (3500 4350)(3500 4300);
WIRE 16 -1 (3250 4400)(3500 4400);
WIRE 16 -1 (3500 4400)(3500 4350);
WIRE 16 -1 (3250 4450)(3500 4450);
WIRE 16 -1 (3500 4450)(3500 4400);
WIRE 16 -1 (3250 4500)(3500 4500);
WIRE 16 -1 (3500 4500)(3500 4450);
WIRE 16 -1 (3250 4550)(3500 4550);
WIRE 16 -1 (3500 4550)(3500 4500);
WIRE 16 -1 (3250 4600)(3500 4600);
WIRE 16 -1 (3500 4600)(3500 4550);
WIRE 16 -1 (3500 4650)(3500 4600);
WIRE 16 -1 (3250 4650)(3500 4650);
WIRE 16 -1 (-4050 700)(-5150 700);
FORCEPROP 2 LAST SIG_NAME PD_CHB_CPU1_DIMM2_SAA
J 0
(-5062 709);
DISPLAY 0.680851 (-5062 709);
PAINT WHITE (-5062 709);
WIRE 16 -1 (-4050 600)(-4050 700);
WIRE 16 -1 (100 1000)(100 875);
WIRE 16 -1 (725 1000)(100 1000);
WIRE 16 -1 (725 875)(725 1000);
WIRE 16 -1 (100 525)(100 675);
WIRE 16 -1 (725 525)(100 525);
WIRE 16 -1 (725 525)(725 675);
DOT 1 (1800 4450);
DOT 1 (1800 4400);
DOT 1 (1800 2050);
DOT 1 (1800 3700);
DOT 1 (3500 1650);
DOT 1 (3500 4600);
DOT 1 (3500 4550);
DOT 1 (3500 4500);
DOT 1 (3500 4450);
DOT 1 (3500 4400);
DOT 1 (3500 4350);
DOT 1 (3500 4300);
DOT 1 (3500 4250);
DOT 1 (3500 4200);
DOT 1 (3500 4150);
DOT 1 (1800 4650);
DOT 1 (1800 4600);
DOT 1 (1800 4350);
DOT 1 (1800 4250);
DOT 1 (1800 4300);
DOT 1 (1800 4150);
DOT 1 (1800 4200);
DOT 1 (3500 4100);
DOT 1 (1800 4100);
DOT 1 (3500 4000);
DOT 1 (3500 4050);
DOT 1 (3500 3950);
DOT 1 (3500 3900);
DOT 1 (3500 3850);
DOT 1 (3500 3800);
DOT 1 (3500 3750);
DOT 1 (3500 3700);
DOT 1 (3500 3650);
DOT 1 (3500 3600);
DOT 1 (3500 3500);
DOT 1 (3500 3550);
DOT 1 (3500 3450);
DOT 1 (3500 3400);
DOT 1 (3500 3350);
DOT 1 (3500 3300);
DOT 1 (3500 3250);
DOT 1 (3500 3200);
DOT 1 (3500 3150);
DOT 1 (3500 3100);
DOT 1 (3500 3050);
DOT 1 (3500 3000);
DOT 1 (3500 2950);
DOT 1 (3500 2900);
DOT 1 (3500 2850);
DOT 1 (3500 2800);
DOT 1 (3500 2750);
DOT 1 (3500 2700);
DOT 1 (3500 2650);
DOT 1 (3500 2600);
DOT 1 (3500 2550);
DOT 1 (3500 2500);
DOT 1 (3500 2450);
DOT 1 (3500 2400);
DOT 1 (3500 2350);
DOT 1 (3500 2300);
DOT 1 (3500 2250);
DOT 1 (3500 2200);
DOT 1 (3500 2150);
DOT 1 (3500 2100);
DOT 1 (3500 2050);
DOT 1 (3500 1950);
DOT 1 (3500 2000);
DOT 1 (3500 1900);
DOT 1 (3500 1850);
DOT 1 (3500 1800);
DOT 1 (3500 1750);
DOT 1 (3500 1700);
DOT 1 (3500 1550);
DOT 1 (3500 1600);
DOT 1 (3500 1500);
DOT 1 (1800 4000);
DOT 1 (1800 4050);
DOT 1 (1800 3900);
DOT 1 (1800 3850);
DOT 1 (1800 3950);
DOT 1 (1800 3800);
DOT 1 (1800 3750);
DOT 1 (1800 3600);
DOT 1 (1800 3650);
DOT 1 (1800 3500);
DOT 1 (1800 3550);
DOT 1 (1800 3400);
DOT 1 (1800 3350);
DOT 1 (1800 3450);
DOT 1 (1800 3250);
DOT 1 (1800 3300);
DOT 1 (1800 3200);
DOT 1 (1800 3150);
DOT 1 (1800 3100);
DOT 1 (1800 3000);
DOT 1 (1800 3050);
DOT 1 (1800 2950);
DOT 1 (1800 2850);
DOT 1 (1800 2900);
DOT 1 (1800 2750);
DOT 1 (1800 2700);
DOT 1 (1800 2800);
DOT 1 (1800 2650);
DOT 1 (1800 2600);
DOT 1 (1800 2450);
DOT 1 (1800 2500);
DOT 1 (1800 2550);
DOT 1 (1800 2350);
DOT 1 (1800 2400);
DOT 1 (1800 2300);
DOT 1 (1800 2200);
DOT 1 (1800 2250);
DOT 1 (1800 2150);
DOT 1 (1800 2100);
DOT 1 (1800 1950);
DOT 1 (1800 2000);
DOT 1 (1800 1900);
DOT 1 (1800 1850);
DOT 1 (1800 1800);
DOT 1 (1800 1700);
DOT 1 (1800 1750);
DOT 1 (1800 1600);
DOT 1 (1800 1650);
DOT 1 (1800 1550);
DOT 1 (1800 1400);
DOT 1 (1800 1500);
DOT 1 (1800 1450);
DOT 1 (725 525);
DOT 1 (100 1000);
DOT 1 (3500 1400);
DOT 1 (3500 1350);
DOT 1 (3500 1300);
FORCENOTE
20210728 MODIFY FOR GT
(-5450 5300) 0;
DISPLAY LEFT (-5450 5300);
DISPLAY 2.510638 (-5450 5300);
PAINT PINK (-5450 5300);
QUIT
